FILE_TYPE = MACRO_DRAWING;
SET COLOR_WIRE YELLOW;
SET COLOR_PROP ORANGE;
SET COLOR_DOT WHITE;
SET COLOR_ARC YELLOW;
SET COLOR_BODY GREEN;
SET COLOR_NOTE PURPLE;
SET PROP_DISPLAY VALUE;
SET PAGE_NUMBER P224;
FORCEADD OFFPAGE..4
(2175 5750);
FORCEPROP 2 LAST $XR0 236 
J 0
(2361 5750);
DISPLAY 0.638298 (2361 5750);
PAINT MONO (2361 5750);
FORCEPROP 2 LAST PATH I1
J 0
(2375 5800);
DISPLAY 1.021277 (2375 5800);
DISPLAY INVISIBLE (2375 5800);
FORCEPROP 2 LAST CDS_LIB standard
J 0
(2175 5750);
PAINT MONO (2175 5750);
DISPLAY INVISIBLE (2175 5750);
FORCEPROP 1 LAST OFFPAGE TRUE
J 0
(2500 5625);
DISPLAY 0.872340 (2500 5625);
DISPLAY INVISIBLE (2500 5625);
FORCEPROP 1 LAST COMMENT_BODY TRUE
J 0
(2150 5650);
DISPLAY 0.872340 (2150 5650);
PAINT GREEN (2150 5650);
DISPLAY INVISIBLE (2150 5650);
FORCEADD Q_RES..2
(-2800 9150);
FORCEPROP 1 LAST PART_NUMBER CS31002FB08
J 0
(-2760 9025);
DISPLAY 0.510638 (-2760 9025);
DISPLAY INVISIBLE (-2760 9025);
FORCEPROP 1 LAST PACK_TYPE 0402LF
J 0
(-2775 9025);
DISPLAY 0.638298 (-2775 9025);
FORCEPROP 1 LAST MATERIAL CHIP
J 0
(-2760 9075);
DISPLAY 0.638298 (-2760 9075);
FORCEPROP 1 LAST WATTAGE 1/16W
J 0
(-2760 9125);
DISPLAY 0.638298 (-2760 9125);
FORCEPROP 1 LAST TOLERANCE 1%
J 0
(-2755 9175);
DISPLAY 0.638298 (-2755 9175);
FORCEPROP 1 LAST VALUE 10K
J 0
(-2755 9225);
DISPLAY 0.638298 (-2755 9225);
FORCEPROP 1 LAST $LOCATION R2312
J 0
(-2755 9275);
DISPLAY 0.978723 (-2755 9275);
FORCEPROP 1 LASTPIN (-2800 9250) $PN 1
J 0
(-2795 9212);
DISPLAY 0.787234 (-2795 9212);
PAINT MONO (-2795 9212);
FORCEPROP 1 LASTPIN (-2800 9050) $PN 2
J 0
(-2795 9060);
DISPLAY 0.787234 (-2795 9060);
PAINT MONO (-2795 9060);
FORCEPROP 1 LAST PATH I101
J 0
(-2750 9325);
DISPLAY 0.978723 (-2750 9325);
PAINT WHITE (-2750 9325);
DISPLAY INVISIBLE (-2750 9325);
FORCEPROP 2 LAST CDS_LIB pure_quanta
J 0
(-2800 9150);
DISPLAY INVISIBLE (-2800 9150);
FORCEPROP 0 LAST CDS_LOCATION R2312
J 0
(-2750 9325);
DISPLAY 1.021277 (-2750 9325);
DISPLAY INVISIBLE (-2750 9325);
FORCEPROP 0 LAST $SEC 1
J 0
(-2750 9325);
DISPLAY 0.680851 (-2750 9325);
PAINT MONO (-2750 9325);
DISPLAY INVISIBLE (-2750 9325);
FORCEPROP 0 LAST CDS_SEC 1
J 0
(-2750 9325);
DISPLAY 1.021277 (-2750 9325);
DISPLAY INVISIBLE (-2750 9325);
FORCEADD UNIVERSAL_POWER..1
(-2800 9500);
FORCEPROP 3 LASTPIN (-2800 9450) SIG_NAME P3V3_AUX\g
J 0
(-2790 9460);
DISPLAY 0.659574 (-2790 9460);
PAINT MONO (-2790 9460);
DISPLAY INVISIBLE (-2790 9460);
FORCEPROP 1 LAST HDL_POWER P3V3_AUX
J 1
(-2800 9550);
DISPLAY 0.872340 (-2800 9550);
PAINT GREEN (-2800 9550);
FORCEPROP 2 LAST CDS_LIB logical_power
J 0
(-2800 9500);
DISPLAY INVISIBLE (-2800 9500);
FORCEPROP 1 LAST PATH I102
J 0
(-2750 9525);
DISPLAY 0.872340 (-2750 9525);
PAINT AQUA (-2750 9525);
DISPLAY INVISIBLE (-2750 9525);
FORCEADD Q_RES..2
(3275 9200);
FORCEPROP 1 LAST PART_NUMBER CS31002FB08
J 0
(3315 9075);
DISPLAY 0.510638 (3315 9075);
DISPLAY INVISIBLE (3315 9075);
FORCEPROP 1 LAST VALUE 10K
J 0
(3320 9275);
DISPLAY 0.638298 (3320 9275);
FORCEPROP 1 LAST TOLERANCE 1%
J 0
(3320 9225);
DISPLAY 0.638298 (3320 9225);
FORCEPROP 1 LAST PACK_TYPE 0402LF
J 0
(3315 9025);
DISPLAY 0.638298 (3315 9025);
FORCEPROP 1 LAST WATTAGE 1/16W
J 0
(3315 9175);
DISPLAY 0.638298 (3315 9175);
FORCEPROP 1 LAST MATERIAL CHIP
J 0
(3315 9125);
DISPLAY 0.638298 (3315 9125);
FORCEPROP 1 LAST $LOCATION R2315
J 0
(3320 9325);
DISPLAY 0.978723 (3320 9325);
FORCEPROP 1 LASTPIN (3275 9300) $PN 1
J 0
(3280 9262);
DISPLAY 0.787234 (3280 9262);
PAINT MONO (3280 9262);
FORCEPROP 1 LASTPIN (3275 9100) $PN 2
J 0
(3280 9110);
DISPLAY 0.787234 (3280 9110);
PAINT MONO (3280 9110);
FORCEPROP 2 LAST CDS_LIB pure_quanta
J 0
(3275 9200);
DISPLAY INVISIBLE (3275 9200);
FORCEPROP 1 LAST PATH I103
J 0
(3325 9375);
DISPLAY 0.978723 (3325 9375);
PAINT WHITE (3325 9375);
DISPLAY INVISIBLE (3325 9375);
FORCEPROP 0 LAST CDS_LOCATION R2315
J 0
(3325 9375);
DISPLAY 1.021277 (3325 9375);
DISPLAY INVISIBLE (3325 9375);
FORCEPROP 0 LAST $SEC 1
J 0
(3325 9375);
DISPLAY 0.680851 (3325 9375);
PAINT MONO (3325 9375);
DISPLAY INVISIBLE (3325 9375);
FORCEPROP 0 LAST CDS_SEC 1
J 0
(3325 9375);
DISPLAY 1.021277 (3325 9375);
DISPLAY INVISIBLE (3325 9375);
FORCEADD UNIVERSAL_POWER..1
(4200 9550);
FORCEPROP 3 LASTPIN (4200 9500) SIG_NAME P3V3_AUX\g
J 0
(4210 9510);
DISPLAY 0.659574 (4210 9510);
PAINT MONO (4210 9510);
DISPLAY INVISIBLE (4210 9510);
FORCEPROP 1 LAST HDL_POWER P3V3_AUX
J 1
(4200 9600);
DISPLAY 0.872340 (4200 9600);
PAINT GREEN (4200 9600);
FORCEPROP 1 LAST PATH I104
J 0
(4250 9575);
DISPLAY 0.872340 (4250 9575);
PAINT AQUA (4250 9575);
DISPLAY INVISIBLE (4250 9575);
FORCEPROP 2 LAST CDS_LIB logical_power
J 0
(4200 9550);
DISPLAY INVISIBLE (4200 9550);
FORCEADD OFFPAGE..1
(-1700 8000);
FORCEPROP 2 LAST $XR0 236 
J 0
(-1982 8000);
DISPLAY 0.638298 (-1982 8000);
PAINT MONO (-1982 8000);
FORCEPROP 1 LAST OFFPAGE TRUE
J 0
(-1375 7875);
DISPLAY 0.872340 (-1375 7875);
PAINT GREEN (-1375 7875);
DISPLAY INVISIBLE (-1375 7875);
FORCEPROP 1 LAST COMMENT_BODY TRUE
J 0
(-1575 7900);
DISPLAY 0.872340 (-1575 7900);
PAINT GREEN (-1575 7900);
DISPLAY INVISIBLE (-1575 7900);
FORCEPROP 2 LAST PATH I105
J 0
(-1975 8050);
DISPLAY 1.021277 (-1975 8050);
DISPLAY INVISIBLE (-1975 8050);
FORCEPROP 2 LAST CDS_LIB standard
J 0
(-1700 8000);
DISPLAY INVISIBLE (-1700 8000);
FORCEADD PCA9545APW..1
(-250 8400);
FORCEPROP 1 LAST PART_NUMBER AL009545K17
J 0
(-545 9134);
DISPLAY 0.723404 (-545 9134);
PAINT GREEN (-545 9134);
DISPLAY INVISIBLE (-545 9134);
FORCEPROP 1 LAST MATERIAL IC
J 0
(-545 9007);
DISPLAY 0.723404 (-545 9007);
PAINT GREEN (-545 9007);
FORCEPROP 2 LAST VALUE PCA9545APW
J 0
(-525 9225);
DISPLAY 1.021277 (-525 9225);
FORCEPROP 2 LAST PART_TYPE SMLF
J 0
(-525 9275);
DISPLAY 1.021277 (-525 9275);
FORCEPROP 1 LAST LOCATION U143
J 0
(-545 9181);
DISPLAY 0.723404 (-545 9181);
PAINT GREEN (-545 9181);
FORCEPROP 2 LASTPIN (-700 7950) $PN 1
J 2
(-710 7960);
DISPLAY 0.680851 (-710 7960);
PAINT MONO (-710 7960);
FORCEPROP 2 LASTPIN (-700 8000) $PN 2
J 2
(-710 8010);
DISPLAY 0.680851 (-710 8010);
PAINT MONO (-710 8010);
FORCEPROP 2 LASTPIN (-700 8800) $PN 17
J 2
(-710 8810);
DISPLAY 0.680851 (-710 8810);
PAINT MONO (-710 8810);
FORCEPROP 2 LASTPIN (200 8800) $PN 4
J 0
(210 8810);
DISPLAY 0.680851 (210 8810);
PAINT MONO (210 8810);
FORCEPROP 2 LASTPIN (200 8500) $PN 7
J 0
(210 8510);
DISPLAY 0.680851 (210 8510);
PAINT MONO (210 8510);
FORCEPROP 2 LASTPIN (200 8200) $PN 11
J 0
(210 8210);
DISPLAY 0.680851 (210 8210);
PAINT MONO (210 8210);
FORCEPROP 2 LASTPIN (200 7900) $PN 14
J 0
(210 7910);
DISPLAY 0.680851 (210 7910);
PAINT MONO (210 7910);
FORCEPROP 2 LASTPIN (-700 8700) $PN 3
J 2
(-710 8710);
DISPLAY 0.680851 (-710 8710);
PAINT MONO (-710 8710);
FORCEPROP 2 LASTPIN (200 8900) $PN 6
J 0
(210 8910);
DISPLAY 0.680851 (210 8910);
PAINT MONO (210 8910);
FORCEPROP 2 LASTPIN (200 8600) $PN 9
J 0
(210 8610);
DISPLAY 0.680851 (210 8610);
PAINT MONO (210 8610);
FORCEPROP 2 LASTPIN (200 8300) $PN 13
J 0
(210 8310);
DISPLAY 0.680851 (210 8310);
PAINT MONO (210 8310);
FORCEPROP 2 LASTPIN (200 8000) $PN 16
J 0
(210 8010);
DISPLAY 0.680851 (210 8010);
PAINT MONO (210 8010);
FORCEPROP 2 LASTPIN (-700 8900) $PN 18
J 2
(-710 8910);
DISPLAY 0.680851 (-710 8910);
PAINT MONO (-710 8910);
FORCEPROP 2 LASTPIN (200 8850) $PN 5
J 0
(210 8860);
DISPLAY 0.680851 (210 8860);
PAINT MONO (210 8860);
FORCEPROP 2 LASTPIN (200 8550) $PN 8
J 0
(210 8560);
DISPLAY 0.680851 (210 8560);
PAINT MONO (210 8560);
FORCEPROP 2 LASTPIN (200 8250) $PN 12
J 0
(210 8260);
DISPLAY 0.680851 (210 8260);
PAINT MONO (210 8260);
FORCEPROP 2 LASTPIN (200 7950) $PN 15
J 0
(210 7960);
DISPLAY 0.680851 (210 7960);
PAINT MONO (210 7960);
FORCEPROP 2 LASTPIN (-700 8850) $PN 19
J 2
(-710 8860);
DISPLAY 0.680851 (-710 8860);
PAINT MONO (-710 8860);
FORCEPROP 2 LASTPIN (-700 8950) $PN 20
J 2
(-710 8960);
DISPLAY 0.680851 (-710 8960);
PAINT MONO (-710 8960);
FORCEPROP 2 LASTPIN (-700 7900) $PN 10
J 2
(-710 7910);
DISPLAY 0.680851 (-710 7910);
PAINT MONO (-710 7910);
FORCEPROP 2 LAST CDS_LIB pure_quanta
J 0
(-250 8400);
DISPLAY INVISIBLE (-250 8400);
FORCEPROP 1 LAST PATH I106
J 0
(-250 8400);
DISPLAY 0.723404 (-250 8400);
PAINT GREEN (-250 8400);
DISPLAY INVISIBLE (-250 8400);
FORCEPROP 1 LAST NEEDS_NO_SIZE TRUE
J 0
(-250 8400);
DISPLAY 0.723404 (-250 8400);
PAINT GREEN (-250 8400);
DISPLAY INVISIBLE (-250 8400);
FORCEPROP 1 LAST CDS_LMAN_SYM_OUTLINE -300,600,300,-600
J 0
(-250 8400);
DISPLAY 0.468085 (-250 8400);
PAINT GREEN (-250 8400);
DISPLAY INVISIBLE (-250 8400);
FORCEPROP 2 LAST SEC_TYPE 
J 0
(-525 9425);
DISPLAY 1.021277 (-525 9425);
DISPLAY INVISIBLE (-525 9425);
FORCEPROP 2 LAST SEC 1
J 0
(-525 9425);
DISPLAY 0.680851 (-525 9425);
PAINT MONO (-525 9425);
DISPLAY INVISIBLE (-525 9425);
FORCEADD OFFPAGE..3
R 2
(-1800 8850);
FORCEPROP 2 LAST $XR1 241 
J 0
(-2230 8850);
DISPLAY 0.638298 (-2230 8850);
PAINT MONO (-2230 8850);
FORCEPROP 2 LAST $XR0 240 
J 0
(-2110 8850);
DISPLAY 0.638298 (-2110 8850);
PAINT MONO (-2110 8850);
FORCEPROP 2 LAST PATH I107
J 2
(-2150 8900);
DISPLAY 1.021277 (-2150 8900);
DISPLAY INVISIBLE (-2150 8900);
FORCEPROP 1 LAST OFFPAGE TRUE
J 2
(-2125 8725);
DISPLAY 0.872340 (-2125 8725);
PAINT GREEN (-2125 8725);
DISPLAY INVISIBLE (-2125 8725);
FORCEPROP 1 LAST COMMENT_BODY TRUE
J 2
(-1750 8750);
DISPLAY 0.872340 (-1750 8750);
PAINT GREEN (-1750 8750);
DISPLAY INVISIBLE (-1750 8750);
FORCEPROP 2 LAST CDS_LIB standard
J 2
(-1800 8850);
DISPLAY INVISIBLE (-1800 8850);
FORCEADD OFFPAGE..4
R 2
(-1800 8900);
FORCEPROP 2 LAST $XR1 241 
J 0
(-2202 8900);
DISPLAY 0.638298 (-2202 8900);
PAINT MONO (-2202 8900);
FORCEPROP 2 LAST $XR0 240 
J 0
(-2082 8900);
DISPLAY 0.638298 (-2082 8900);
PAINT MONO (-2082 8900);
FORCEPROP 2 LAST PATH I108
J 2
(-2125 8950);
DISPLAY 1.021277 (-2125 8950);
DISPLAY INVISIBLE (-2125 8950);
FORCEPROP 1 LAST COMMENT_BODY TRUE
J 2
(-1775 8800);
DISPLAY 0.872340 (-1775 8800);
PAINT GREEN (-1775 8800);
DISPLAY INVISIBLE (-1775 8800);
FORCEPROP 1 LAST OFFPAGE TRUE
J 2
(-2125 8775);
DISPLAY 0.872340 (-2125 8775);
DISPLAY INVISIBLE (-2125 8775);
FORCEPROP 2 LAST CDS_LIB standard
J 2
(-1800 8900);
DISPLAY INVISIBLE (-1800 8900);
FORCEADD Q_RES..2
(3600 9200);
FORCEPROP 1 LAST PART_NUMBER CS31002FB08
J 0
(3640 9075);
DISPLAY 0.510638 (3640 9075);
DISPLAY INVISIBLE (3640 9075);
FORCEPROP 1 LAST TOLERANCE 1%
J 0
(3645 9225);
DISPLAY 0.638298 (3645 9225);
FORCEPROP 1 LAST VALUE 10K
J 0
(3645 9275);
DISPLAY 0.638298 (3645 9275);
FORCEPROP 1 LAST PACK_TYPE 0402LF
J 0
(3640 9025);
DISPLAY 0.638298 (3640 9025);
FORCEPROP 1 LAST MATERIAL CHIP
J 0
(3640 9125);
DISPLAY 0.638298 (3640 9125);
FORCEPROP 1 LAST WATTAGE 1/16W
J 0
(3640 9175);
DISPLAY 0.638298 (3640 9175);
FORCEPROP 1 LAST $LOCATION R3127
J 0
(3645 9325);
DISPLAY 0.978723 (3645 9325);
FORCEPROP 1 LASTPIN (3600 9300) $PN 1
J 0
(3605 9262);
DISPLAY 0.787234 (3605 9262);
PAINT MONO (3605 9262);
FORCEPROP 1 LASTPIN (3600 9100) $PN 2
J 0
(3605 9110);
DISPLAY 0.787234 (3605 9110);
PAINT MONO (3605 9110);
FORCEPROP 1 LAST PATH I109
J 0
(3650 9375);
DISPLAY 0.978723 (3650 9375);
PAINT WHITE (3650 9375);
DISPLAY INVISIBLE (3650 9375);
FORCEPROP 2 LAST CDS_LIB pure_quanta
J 0
(3600 9200);
DISPLAY INVISIBLE (3600 9200);
FORCEPROP 0 LAST CDS_LOCATION R3127
J 0
(3650 9375);
DISPLAY 1.021277 (3650 9375);
DISPLAY INVISIBLE (3650 9375);
FORCEPROP 0 LAST $SEC 1
J 0
(3650 9375);
DISPLAY 0.680851 (3650 9375);
PAINT MONO (3650 9375);
DISPLAY INVISIBLE (3650 9375);
FORCEPROP 0 LAST CDS_SEC 1
J 0
(3650 9375);
DISPLAY 1.021277 (3650 9375);
DISPLAY INVISIBLE (3650 9375);
FORCEADD Q_RES..2
(3900 9200);
FORCEPROP 1 LAST PART_NUMBER CS31002FB08
J 0
(3940 9075);
DISPLAY 0.510638 (3940 9075);
DISPLAY INVISIBLE (3940 9075);
FORCEPROP 1 LAST PACK_TYPE 0402LF
J 0
(3940 9025);
DISPLAY 0.638298 (3940 9025);
FORCEPROP 1 LAST MATERIAL CHIP
J 0
(3940 9125);
DISPLAY 0.638298 (3940 9125);
FORCEPROP 1 LAST WATTAGE 1/16W
J 0
(3940 9175);
DISPLAY 0.638298 (3940 9175);
FORCEPROP 1 LAST VALUE 10K
J 0
(3945 9275);
DISPLAY 0.638298 (3945 9275);
FORCEPROP 1 LAST TOLERANCE 1%
J 0
(3945 9225);
DISPLAY 0.638298 (3945 9225);
FORCEPROP 1 LAST $LOCATION R3130
J 0
(3945 9325);
DISPLAY 0.978723 (3945 9325);
FORCEPROP 1 LASTPIN (3900 9300) $PN 1
J 0
(3905 9262);
DISPLAY 0.787234 (3905 9262);
PAINT MONO (3905 9262);
FORCEPROP 1 LASTPIN (3900 9100) $PN 2
J 0
(3905 9110);
DISPLAY 0.787234 (3905 9110);
PAINT MONO (3905 9110);
FORCEPROP 1 LAST PATH I110
J 0
(3950 9375);
DISPLAY 0.978723 (3950 9375);
PAINT WHITE (3950 9375);
DISPLAY INVISIBLE (3950 9375);
FORCEPROP 2 LAST CDS_LIB pure_quanta
J 0
(3900 9200);
DISPLAY INVISIBLE (3900 9200);
FORCEPROP 0 LAST CDS_LOCATION R3130
J 0
(3950 9375);
DISPLAY 1.021277 (3950 9375);
DISPLAY INVISIBLE (3950 9375);
FORCEPROP 0 LAST $SEC 1
J 0
(3950 9375);
DISPLAY 0.680851 (3950 9375);
PAINT MONO (3950 9375);
DISPLAY INVISIBLE (3950 9375);
FORCEPROP 0 LAST CDS_SEC 1
J 0
(3950 9375);
DISPLAY 1.021277 (3950 9375);
DISPLAY INVISIBLE (3950 9375);
FORCEADD Q_RES..2
(4200 9200);
FORCEPROP 1 LAST PART_NUMBER CS31002FB08
J 0
(4240 9075);
DISPLAY 0.510638 (4240 9075);
DISPLAY INVISIBLE (4240 9075);
FORCEPROP 1 LAST PACK_TYPE 0402LF
J 0
(4240 9025);
DISPLAY 0.638298 (4240 9025);
FORCEPROP 1 LAST MATERIAL CHIP
J 0
(4240 9125);
DISPLAY 0.638298 (4240 9125);
FORCEPROP 1 LAST WATTAGE 1/16W
J 0
(4240 9175);
DISPLAY 0.638298 (4240 9175);
FORCEPROP 1 LAST TOLERANCE 1%
J 0
(4245 9225);
DISPLAY 0.638298 (4245 9225);
FORCEPROP 1 LAST VALUE 10K
J 0
(4245 9275);
DISPLAY 0.638298 (4245 9275);
FORCEPROP 1 LAST $LOCATION R3131
J 0
(4245 9325);
DISPLAY 0.978723 (4245 9325);
FORCEPROP 1 LASTPIN (4200 9300) $PN 1
J 0
(4205 9262);
DISPLAY 0.787234 (4205 9262);
PAINT MONO (4205 9262);
FORCEPROP 1 LASTPIN (4200 9100) $PN 2
J 0
(4205 9110);
DISPLAY 0.787234 (4205 9110);
PAINT MONO (4205 9110);
FORCEPROP 2 LAST CDS_LIB pure_quanta
J 0
(4200 9200);
DISPLAY INVISIBLE (4200 9200);
FORCEPROP 1 LAST PATH I111
J 0
(4250 9375);
DISPLAY 0.978723 (4250 9375);
PAINT WHITE (4250 9375);
DISPLAY INVISIBLE (4250 9375);
FORCEPROP 0 LAST CDS_LOCATION R3131
J 0
(4250 9375);
DISPLAY 1.021277 (4250 9375);
DISPLAY INVISIBLE (4250 9375);
FORCEPROP 0 LAST $SEC 1
J 0
(4250 9375);
DISPLAY 0.680851 (4250 9375);
PAINT MONO (4250 9375);
DISPLAY INVISIBLE (4250 9375);
FORCEPROP 0 LAST CDS_SEC 1
J 0
(4250 9375);
DISPLAY 1.021277 (4250 9375);
DISPLAY INVISIBLE (4250 9375);
FORCEADD OFFPAGE..3
(2925 8250);
FORCEPROP 2 LAST $XR1 236 
J 0
(3229 8250);
DISPLAY 0.638298 (3229 8250);
PAINT MONO (3229 8250);
FORCEPROP 2 LAST $XR0 14 
J 0
(3139 8250);
DISPLAY 0.638298 (3139 8250);
PAINT MONO (3139 8250);
FORCEPROP 2 LAST PATH I112
J 0
(3150 8300);
DISPLAY 1.021277 (3150 8300);
DISPLAY INVISIBLE (3150 8300);
FORCEPROP 1 LAST COMMENT_BODY TRUE
J 0
(2875 8150);
DISPLAY 0.872340 (2875 8150);
PAINT GREEN (2875 8150);
DISPLAY INVISIBLE (2875 8150);
FORCEPROP 1 LAST OFFPAGE TRUE
J 0
(3250 8125);
DISPLAY 0.872340 (3250 8125);
PAINT GREEN (3250 8125);
DISPLAY INVISIBLE (3250 8125);
FORCEPROP 2 LAST CDS_LIB standard
J 0
(2925 8250);
PAINT MONO (2925 8250);
DISPLAY INVISIBLE (2925 8250);
FORCEADD OFFPAGE..2
(2925 8300);
FORCEPROP 2 LAST $XR1 14 
J 0
(3234 8300);
DISPLAY 0.638298 (3234 8300);
PAINT MONO (3234 8300);
FORCEPROP 2 LAST $XR0 236 
J 0
(3114 8300);
DISPLAY 0.638298 (3114 8300);
PAINT MONO (3114 8300);
FORCEPROP 2 LAST PATH I113
J 0
(3125 8350);
DISPLAY 1.021277 (3125 8350);
DISPLAY INVISIBLE (3125 8350);
FORCEPROP 2 LAST CDS_LIB standard
J 0
(2925 8300);
PAINT MONO (2925 8300);
DISPLAY INVISIBLE (2925 8300);
FORCEPROP 1 LAST COMMENT_BODY TRUE
J 0
(2880 8205);
DISPLAY 0.872340 (2880 8205);
PAINT GREEN (2880 8205);
DISPLAY INVISIBLE (2880 8205);
FORCEPROP 1 LAST OFFPAGE TRUE
J 0
(3250 8175);
DISPLAY 0.872340 (3250 8175);
PAINT GREEN (3250 8175);
DISPLAY INVISIBLE (3250 8175);
FORCEADD Q_RES..1
(1475 8250);
FORCEPROP 1 LAST PART_NUMBER CS00002JB13
J 0
(1425 8300);
DISPLAY 0.404255 (1425 8300);
DISPLAY INVISIBLE (1425 8300);
FORCEPROP 1 LAST MATERIAL CHIP
J 0
(1725 8250);
DISPLAY 0.510638 (1725 8250);
FORCEPROP 1 LAST VALUE 0
J 2
(1625 8250);
DISPLAY 0.510638 (1625 8250);
FORCEPROP 1 LAST TOLERANCE 5%
J 0
(1650 8250);
DISPLAY 0.510638 (1650 8250);
FORCEPROP 1 LAST $LOCATION R3124
J 0
(1300 8250);
DISPLAY 0.510638 (1300 8250);
FORCEPROP 1 LASTPIN (1375 8250) $PN 1
J 0
(1387 8262);
DISPLAY 0.787234 (1387 8262);
PAINT MONO (1387 8262);
FORCEPROP 1 LASTPIN (1575 8250) $PN 2
J 0
(1537 8262);
DISPLAY 0.787234 (1537 8262);
PAINT MONO (1537 8262);
FORCEPROP 1 LAST PATH I114
J 0
(1425 8400);
DISPLAY 0.978723 (1425 8400);
PAINT WHITE (1425 8400);
DISPLAY INVISIBLE (1425 8400);
FORCEPROP 1 LAST PACK_TYPE 0402LF
J 0
(1725 8250);
DISPLAY 0.510638 (1725 8250);
DISPLAY INVISIBLE (1725 8250);
FORCEPROP 1 LAST WATTAGE 1/16W
J 2
(1650 8325);
DISPLAY 0.404255 (1650 8325);
DISPLAY INVISIBLE (1650 8325);
FORCEPROP 2 LAST CDS_LIB pure_quanta
J 0
(1475 8250);
DISPLAY INVISIBLE (1475 8250);
FORCEPROP 0 LAST CDS_LOCATION R3124
J 0
(1225 8300);
DISPLAY 1.021277 (1225 8300);
DISPLAY INVISIBLE (1225 8300);
FORCEPROP 0 LAST $SEC 1
J 0
(1225 8300);
DISPLAY 0.680851 (1225 8300);
PAINT MONO (1225 8300);
DISPLAY INVISIBLE (1225 8300);
FORCEPROP 0 LAST CDS_SEC 1
J 0
(1225 8300);
DISPLAY 1.021277 (1225 8300);
DISPLAY INVISIBLE (1225 8300);
FORCEADD Q_RES..1
(1475 8300);
FORCEPROP 1 LAST PART_NUMBER CS00002JB13
J 0
(1425 8350);
DISPLAY 0.404255 (1425 8350);
DISPLAY INVISIBLE (1425 8350);
FORCEPROP 1 LAST MATERIAL CHIP
J 0
(1725 8300);
DISPLAY 0.510638 (1725 8300);
FORCEPROP 1 LAST TOLERANCE 5%
J 0
(1650 8300);
DISPLAY 0.510638 (1650 8300);
FORCEPROP 1 LAST VALUE 0
J 2
(1625 8300);
DISPLAY 0.510638 (1625 8300);
FORCEPROP 1 LAST $LOCATION R3123
J 0
(1300 8300);
DISPLAY 0.510638 (1300 8300);
FORCEPROP 1 LASTPIN (1375 8300) $PN 1
J 0
(1387 8312);
DISPLAY 0.787234 (1387 8312);
PAINT MONO (1387 8312);
FORCEPROP 1 LASTPIN (1575 8300) $PN 2
J 0
(1537 8312);
DISPLAY 0.787234 (1537 8312);
PAINT MONO (1537 8312);
FORCEPROP 1 LAST PATH I115
J 0
(1425 8450);
DISPLAY 0.978723 (1425 8450);
PAINT WHITE (1425 8450);
DISPLAY INVISIBLE (1425 8450);
FORCEPROP 2 LAST CDS_LIB pure_quanta
J 0
(1475 8300);
DISPLAY INVISIBLE (1475 8300);
FORCEPROP 1 LAST WATTAGE 1/16W
J 2
(1650 8375);
DISPLAY 0.404255 (1650 8375);
DISPLAY INVISIBLE (1650 8375);
FORCEPROP 1 LAST PACK_TYPE 0402LF
J 0
(1725 8300);
DISPLAY 0.510638 (1725 8300);
DISPLAY INVISIBLE (1725 8300);
FORCEPROP 0 LAST CDS_LOCATION R3123
J 0
(1225 8350);
DISPLAY 1.021277 (1225 8350);
DISPLAY INVISIBLE (1225 8350);
FORCEPROP 0 LAST $SEC 1
J 0
(1225 8350);
DISPLAY 0.680851 (1225 8350);
PAINT MONO (1225 8350);
DISPLAY INVISIBLE (1225 8350);
FORCEPROP 0 LAST CDS_SEC 1
J 0
(1225 8350);
DISPLAY 1.021277 (1225 8350);
DISPLAY INVISIBLE (1225 8350);
FORCEADD Q_RES..1
(1475 8000);
FORCEPROP 1 LAST PART_NUMBER CS00002JB13
J 0
(1425 8050);
DISPLAY 0.404255 (1425 8050);
DISPLAY INVISIBLE (1425 8050);
FORCEPROP 1 LAST VALUE 0
J 2
(1625 8000);
DISPLAY 0.510638 (1625 8000);
FORCEPROP 1 LAST MATERIAL CHIP
J 0
(1725 8000);
DISPLAY 0.510638 (1725 8000);
FORCEPROP 1 LAST TOLERANCE 5%
J 0
(1650 8000);
DISPLAY 0.510638 (1650 8000);
FORCEPROP 1 LAST $LOCATION R3125
J 0
(1300 8000);
DISPLAY 0.510638 (1300 8000);
FORCEPROP 1 LASTPIN (1375 8000) $PN 1
J 0
(1387 8012);
DISPLAY 0.787234 (1387 8012);
PAINT MONO (1387 8012);
FORCEPROP 1 LASTPIN (1575 8000) $PN 2
J 0
(1537 8012);
DISPLAY 0.787234 (1537 8012);
PAINT MONO (1537 8012);
FORCEPROP 1 LAST PATH I116
J 0
(1425 8150);
DISPLAY 0.978723 (1425 8150);
PAINT WHITE (1425 8150);
DISPLAY INVISIBLE (1425 8150);
FORCEPROP 1 LAST PACK_TYPE 0402LF
J 0
(1725 8000);
DISPLAY 0.510638 (1725 8000);
DISPLAY INVISIBLE (1725 8000);
FORCEPROP 1 LAST WATTAGE 1/16W
J 2
(1650 8075);
DISPLAY 0.404255 (1650 8075);
DISPLAY INVISIBLE (1650 8075);
FORCEPROP 2 LAST CDS_LIB pure_quanta
J 0
(1475 8000);
DISPLAY INVISIBLE (1475 8000);
FORCEPROP 0 LAST CDS_LOCATION R3125
J 0
(1225 8050);
DISPLAY 1.021277 (1225 8050);
DISPLAY INVISIBLE (1225 8050);
FORCEPROP 0 LAST $SEC 1
J 0
(1225 8050);
DISPLAY 0.680851 (1225 8050);
PAINT MONO (1225 8050);
DISPLAY INVISIBLE (1225 8050);
FORCEPROP 0 LAST CDS_SEC 1
J 0
(1225 8050);
DISPLAY 1.021277 (1225 8050);
DISPLAY INVISIBLE (1225 8050);
FORCEADD Q_RES..1
(1475 7950);
FORCEPROP 1 LAST PART_NUMBER CS00002JB13
J 0
(1425 8000);
DISPLAY 0.404255 (1425 8000);
DISPLAY INVISIBLE (1425 8000);
FORCEPROP 1 LAST MATERIAL CHIP
J 0
(1725 7950);
DISPLAY 0.510638 (1725 7950);
FORCEPROP 1 LAST TOLERANCE 5%
J 0
(1650 7950);
DISPLAY 0.510638 (1650 7950);
FORCEPROP 1 LAST VALUE 0
J 2
(1625 7950);
DISPLAY 0.510638 (1625 7950);
FORCEPROP 1 LAST $LOCATION R3126
J 0
(1300 7950);
DISPLAY 0.510638 (1300 7950);
FORCEPROP 1 LASTPIN (1375 7950) $PN 1
J 0
(1387 7962);
DISPLAY 0.787234 (1387 7962);
PAINT MONO (1387 7962);
FORCEPROP 1 LASTPIN (1575 7950) $PN 2
J 0
(1537 7962);
DISPLAY 0.787234 (1537 7962);
PAINT MONO (1537 7962);
FORCEPROP 1 LAST PATH I117
J 0
(1425 8100);
DISPLAY 0.978723 (1425 8100);
PAINT WHITE (1425 8100);
DISPLAY INVISIBLE (1425 8100);
FORCEPROP 2 LAST CDS_LIB pure_quanta
J 0
(1475 7950);
DISPLAY INVISIBLE (1475 7950);
FORCEPROP 1 LAST WATTAGE 1/16W
J 2
(1650 8025);
DISPLAY 0.404255 (1650 8025);
DISPLAY INVISIBLE (1650 8025);
FORCEPROP 1 LAST PACK_TYPE 0402LF
J 0
(1725 7950);
DISPLAY 0.510638 (1725 7950);
DISPLAY INVISIBLE (1725 7950);
FORCEPROP 0 LAST CDS_LOCATION R3126
J 0
(1225 8000);
DISPLAY 1.021277 (1225 8000);
DISPLAY INVISIBLE (1225 8000);
FORCEPROP 0 LAST $SEC 1
J 0
(1225 8000);
DISPLAY 0.680851 (1225 8000);
PAINT MONO (1225 8000);
DISPLAY INVISIBLE (1225 8000);
FORCEPROP 0 LAST CDS_SEC 1
J 0
(1225 8000);
DISPLAY 1.021277 (1225 8000);
DISPLAY INVISIBLE (1225 8000);
FORCEADD OFFPAGE..2
(2925 8000);
FORCEPROP 2 LAST $XR1 45 
J 0
(3234 8000);
DISPLAY 0.638298 (3234 8000);
PAINT MONO (3234 8000);
FORCEPROP 2 LAST $XR0 236 
J 0
(3114 8000);
DISPLAY 0.638298 (3114 8000);
PAINT MONO (3114 8000);
FORCEPROP 2 LAST PATH I118
J 0
(3125 8050);
DISPLAY 1.021277 (3125 8050);
DISPLAY INVISIBLE (3125 8050);
FORCEPROP 1 LAST OFFPAGE TRUE
J 0
(3250 7875);
DISPLAY 0.872340 (3250 7875);
PAINT GREEN (3250 7875);
DISPLAY INVISIBLE (3250 7875);
FORCEPROP 1 LAST COMMENT_BODY TRUE
J 0
(2880 7905);
DISPLAY 0.872340 (2880 7905);
PAINT GREEN (2880 7905);
DISPLAY INVISIBLE (2880 7905);
FORCEPROP 2 LAST CDS_LIB standard
J 0
(2925 8000);
PAINT MONO (2925 8000);
DISPLAY INVISIBLE (2925 8000);
FORCEADD OFFPAGE..3
(2925 7950);
FORCEPROP 2 LAST $XR1 236 
J 0
(3229 7950);
DISPLAY 0.638298 (3229 7950);
PAINT MONO (3229 7950);
FORCEPROP 2 LAST $XR0 45 
J 0
(3139 7950);
DISPLAY 0.638298 (3139 7950);
PAINT MONO (3139 7950);
FORCEPROP 2 LAST PATH I119
J 0
(3150 8000);
DISPLAY 1.021277 (3150 8000);
DISPLAY INVISIBLE (3150 8000);
FORCEPROP 2 LAST CDS_LIB standard
J 0
(2925 7950);
PAINT MONO (2925 7950);
DISPLAY INVISIBLE (2925 7950);
FORCEPROP 1 LAST OFFPAGE TRUE
J 0
(3250 7825);
DISPLAY 0.872340 (3250 7825);
PAINT GREEN (3250 7825);
DISPLAY INVISIBLE (3250 7825);
FORCEPROP 1 LAST COMMENT_BODY TRUE
J 0
(2875 7850);
DISPLAY 0.872340 (2875 7850);
PAINT GREEN (2875 7850);
DISPLAY INVISIBLE (2875 7850);
FORCEADD OFFPAGE..5
(2150 6500);
FORCEPROP 2 LAST $XR1 45 
J 0
(1805 6500);
DISPLAY 0.638298 (1805 6500);
PAINT MONO (1805 6500);
FORCEPROP 2 LAST $XR0 236 
J 0
(1895 6500);
DISPLAY 0.638298 (1895 6500);
PAINT MONO (1895 6500);
FORCEPROP 1 LAST OFFPAGE TRUE
J 0
(2475 6375);
DISPLAY 0.872340 (2475 6375);
PAINT GREEN (2475 6375);
DISPLAY INVISIBLE (2475 6375);
FORCEPROP 1 LAST COMMENT_BODY TRUE
J 0
(2250 6425);
DISPLAY 0.872340 (2250 6425);
PAINT PEACH (2250 6425);
DISPLAY INVISIBLE (2250 6425);
FORCEPROP 2 LAST CDS_LIB standard
J 0
(2150 6500);
PAINT MONO (2150 6500);
DISPLAY INVISIBLE (2150 6500);
FORCEPROP 2 LAST PATH I123
J 0
(1875 6550);
DISPLAY 1.021277 (1875 6550);
DISPLAY INVISIBLE (1875 6550);
FORCEADD OFFPAGE..5
(2150 6750);
FORCEPROP 2 LAST $XR1 236 
J 0
(1806 6750);
DISPLAY 0.638298 (1806 6750);
PAINT MONO (1806 6750);
FORCEPROP 2 LAST $XR0 14 
J 0
(1926 6750);
DISPLAY 0.638298 (1926 6750);
PAINT MONO (1926 6750);
FORCEPROP 1 LAST OFFPAGE TRUE
J 0
(2475 6625);
DISPLAY 0.872340 (2475 6625);
PAINT GREEN (2475 6625);
DISPLAY INVISIBLE (2475 6625);
FORCEPROP 1 LAST COMMENT_BODY TRUE
J 0
(2250 6675);
DISPLAY 0.872340 (2250 6675);
PAINT PEACH (2250 6675);
DISPLAY INVISIBLE (2250 6675);
FORCEPROP 2 LAST CDS_LIB standard
J 0
(2150 6750);
PAINT MONO (2150 6750);
DISPLAY INVISIBLE (2150 6750);
FORCEPROP 2 LAST PATH I124
J 0
(1875 6800);
DISPLAY 1.021277 (1875 6800);
DISPLAY INVISIBLE (1875 6800);
FORCEADD OFFPAGE..5
(2150 6800);
FORCEPROP 2 LAST $XR1 14 
J 0
(1805 6800);
DISPLAY 0.638298 (1805 6800);
PAINT MONO (1805 6800);
FORCEPROP 2 LAST $XR0 236 
J 0
(1895 6800);
DISPLAY 0.638298 (1895 6800);
PAINT MONO (1895 6800);
FORCEPROP 1 LAST OFFPAGE TRUE
J 0
(2475 6675);
DISPLAY 0.872340 (2475 6675);
PAINT GREEN (2475 6675);
DISPLAY INVISIBLE (2475 6675);
FORCEPROP 1 LAST COMMENT_BODY TRUE
J 0
(2250 6725);
DISPLAY 0.872340 (2250 6725);
PAINT PEACH (2250 6725);
DISPLAY INVISIBLE (2250 6725);
FORCEPROP 2 LAST CDS_LIB standard
J 0
(2150 6800);
PAINT MONO (2150 6800);
DISPLAY INVISIBLE (2150 6800);
FORCEPROP 2 LAST PATH I125
J 0
(1875 6850);
DISPLAY 1.021277 (1875 6850);
DISPLAY INVISIBLE (1875 6850);
FORCEADD Q_RES..2
(1750 4800);
FORCEPROP 1 LAST PART_NUMBER CS00002JB13
J 0
(1790 4625);
DISPLAY 0.638298 (1790 4625);
DISPLAY INVISIBLE (1790 4625);
FORCEPROP 1 LAST VALUE 0
J 0
(1795 4875);
DISPLAY 0.638298 (1795 4875);
FORCEPROP 1 LAST MATERIAL EMPTY
J 0
(1790 4725);
DISPLAY 0.638298 (1790 4725);
PAINT RED (1790 4725);
FORCEPROP 1 LAST WATTAGE 1/16W
J 0
(1790 4775);
DISPLAY 0.638298 (1790 4775);
FORCEPROP 1 LAST TOLERANCE 5%
J 0
(1795 4825);
DISPLAY 0.638298 (1795 4825);
FORCEPROP 1 LAST PACK_TYPE 0402LF
J 0
(1790 4675);
DISPLAY 0.638298 (1790 4675);
FORCEPROP 1 LAST $LOCATION R448
J 0
(1795 4925);
DISPLAY 0.638298 (1795 4925);
FORCEPROP 1 LASTPIN (1750 4900) $PN 1
J 0
(1755 4862);
DISPLAY 0.787234 (1755 4862);
FORCEPROP 1 LASTPIN (1750 4700) $PN 2
J 0
(1755 4710);
DISPLAY 0.787234 (1755 4710);
FORCEPROP 1 LAST PATH I13
J 0
(1800 4975);
DISPLAY 0.978723 (1800 4975);
PAINT WHITE (1800 4975);
DISPLAY INVISIBLE (1800 4975);
FORCEPROP 2 LAST CDS_LIB pure_quanta
J 0
(1750 4800);
PAINT MONO (1750 4800);
DISPLAY INVISIBLE (1750 4800);
FORCEPROP 2 LAST CDS_LOCATION R448
J 0
(1800 5025);
DISPLAY 1.021277 (1800 5025);
DISPLAY INVISIBLE (1800 5025);
FORCEPROP 2 LAST $SEC 1
J 0
(1800 5025);
DISPLAY 0.680851 (1800 5025);
PAINT MONO (1800 5025);
DISPLAY INVISIBLE (1800 5025);
FORCEPROP 2 LAST CDS_SEC 1
J 0
(1800 5025);
DISPLAY 1.021277 (1800 5025);
DISPLAY INVISIBLE (1800 5025);
FORCEADD Q_RES..1
(3650 6450);
FORCEPROP 1 LAST PART_NUMBER CS22002FB07
J 0
(3525 6500);
DISPLAY 0.638298 (3525 6500);
DISPLAY INVISIBLE (3525 6500);
FORCEPROP 1 LAST TOLERANCE 1%
J 0
(3925 6450);
DISPLAY 0.638298 (3925 6450);
FORCEPROP 1 LAST VALUE 2K
J 2
(3875 6450);
DISPLAY 0.638298 (3875 6450);
FORCEPROP 1 LAST MATERIAL CHIP
J 0
(4025 6450);
DISPLAY 0.638298 (4025 6450);
FORCEPROP 1 LAST $LOCATION R3225
J 0
(3375 6450);
DISPLAY 0.638298 (3375 6450);
FORCEPROP 1 LASTPIN (3550 6450) $PN 1
J 0
(3562 6462);
DISPLAY 0.787234 (3562 6462);
FORCEPROP 1 LASTPIN (3750 6450) $PN 2
J 0
(3712 6462);
DISPLAY 0.787234 (3712 6462);
FORCEPROP 1 LAST WATTAGE 1/16W
J 2
(3950 6550);
DISPLAY 0.638298 (3950 6550);
DISPLAY INVISIBLE (3950 6550);
FORCEPROP 1 LAST PACK_TYPE 0402LF
J 0
(3525 6550);
DISPLAY 0.638298 (3525 6550);
DISPLAY INVISIBLE (3525 6550);
FORCEPROP 2 LAST CDS_LIB pure_quanta
J 0
(3650 6450);
PAINT MONO (3650 6450);
DISPLAY INVISIBLE (3650 6450);
FORCEPROP 1 LAST PATH I130
J 0
(3600 6600);
DISPLAY 0.978723 (3600 6600);
PAINT WHITE (3600 6600);
DISPLAY INVISIBLE (3600 6600);
FORCEPROP 2 LAST CDS_LOCATION R3225
J 0
(3600 6650);
DISPLAY 1.021277 (3600 6650);
DISPLAY INVISIBLE (3600 6650);
FORCEPROP 2 LAST $SEC 1
J 0
(3600 6650);
DISPLAY 0.680851 (3600 6650);
PAINT MONO (3600 6650);
DISPLAY INVISIBLE (3600 6650);
FORCEPROP 2 LAST CDS_SEC 1
J 0
(3600 6650);
DISPLAY 1.021277 (3600 6650);
DISPLAY INVISIBLE (3600 6650);
FORCEADD Q_RES..1
(3650 6500);
FORCEPROP 1 LAST PART_NUMBER CS22002FB07
J 0
(3525 6575);
DISPLAY 0.638298 (3525 6575);
DISPLAY INVISIBLE (3525 6575);
FORCEPROP 1 LAST WATTAGE 1/16W
J 2
(3900 6625);
DISPLAY 0.638298 (3900 6625);
FORCEPROP 1 LAST VALUE 2K
J 2
(3875 6500);
DISPLAY 0.638298 (3875 6500);
FORCEPROP 1 LAST MATERIAL CHIP
J 0
(4025 6500);
DISPLAY 0.638298 (4025 6500);
FORCEPROP 1 LAST TOLERANCE 1%
J 0
(3925 6500);
DISPLAY 0.638298 (3925 6500);
FORCEPROP 1 LAST PACK_TYPE 0402LF
J 0
(3525 6625);
DISPLAY 0.638298 (3525 6625);
FORCEPROP 1 LAST $LOCATION R3224
J 0
(3375 6500);
DISPLAY 0.638298 (3375 6500);
FORCEPROP 1 LASTPIN (3550 6500) $PN 1
J 0
(3562 6512);
DISPLAY 0.787234 (3562 6512);
FORCEPROP 1 LASTPIN (3750 6500) $PN 2
J 0
(3712 6512);
DISPLAY 0.787234 (3712 6512);
FORCEPROP 2 LAST CDS_LIB pure_quanta
J 0
(3650 6500);
PAINT MONO (3650 6500);
DISPLAY INVISIBLE (3650 6500);
FORCEPROP 1 LAST PATH I131
J 0
(3600 6650);
DISPLAY 0.978723 (3600 6650);
PAINT WHITE (3600 6650);
DISPLAY INVISIBLE (3600 6650);
FORCEPROP 2 LAST CDS_LOCATION R3224
J 0
(3600 6700);
DISPLAY 1.021277 (3600 6700);
DISPLAY INVISIBLE (3600 6700);
FORCEPROP 2 LAST $SEC 1
J 0
(3600 6700);
DISPLAY 0.680851 (3600 6700);
PAINT MONO (3600 6700);
DISPLAY INVISIBLE (3600 6700);
FORCEPROP 2 LAST CDS_SEC 1
J 0
(3600 6700);
DISPLAY 1.021277 (3600 6700);
DISPLAY INVISIBLE (3600 6700);
FORCEADD Q_RES..1
(3650 6800);
FORCEPROP 1 LAST PART_NUMBER CS22002FB07
J 0
(3525 6875);
DISPLAY 0.638298 (3525 6875);
DISPLAY INVISIBLE (3525 6875);
FORCEPROP 1 LAST PACK_TYPE 0402LF
J 0
(3525 6925);
DISPLAY 0.638298 (3525 6925);
FORCEPROP 1 LAST MATERIAL CHIP
J 0
(4025 6800);
DISPLAY 0.638298 (4025 6800);
FORCEPROP 1 LAST VALUE 2K
J 2
(3875 6800);
DISPLAY 0.638298 (3875 6800);
FORCEPROP 1 LAST WATTAGE 1/16W
J 2
(3900 6925);
DISPLAY 0.638298 (3900 6925);
FORCEPROP 1 LAST TOLERANCE 1%
J 0
(3925 6800);
DISPLAY 0.638298 (3925 6800);
FORCEPROP 1 LAST $LOCATION R3222
J 0
(3375 6800);
DISPLAY 0.638298 (3375 6800);
FORCEPROP 1 LASTPIN (3550 6800) $PN 1
J 0
(3562 6812);
DISPLAY 0.787234 (3562 6812);
FORCEPROP 1 LASTPIN (3750 6800) $PN 2
J 0
(3712 6812);
DISPLAY 0.787234 (3712 6812);
FORCEPROP 2 LAST CDS_LIB pure_quanta
J 0
(3650 6800);
PAINT MONO (3650 6800);
DISPLAY INVISIBLE (3650 6800);
FORCEPROP 1 LAST PATH I132
J 0
(3600 6950);
DISPLAY 0.978723 (3600 6950);
PAINT WHITE (3600 6950);
DISPLAY INVISIBLE (3600 6950);
FORCEPROP 2 LAST CDS_LOCATION R3222
J 0
(3600 7000);
DISPLAY 1.021277 (3600 7000);
DISPLAY INVISIBLE (3600 7000);
FORCEPROP 2 LAST $SEC 1
J 0
(3600 7000);
DISPLAY 0.680851 (3600 7000);
PAINT MONO (3600 7000);
DISPLAY INVISIBLE (3600 7000);
FORCEPROP 2 LAST CDS_SEC 1
J 0
(3600 7000);
DISPLAY 1.021277 (3600 7000);
DISPLAY INVISIBLE (3600 7000);
FORCEADD Q_RES..1
(3650 6750);
FORCEPROP 1 LAST PART_NUMBER CS22002FB07
J 0
(3525 6800);
DISPLAY 0.638298 (3525 6800);
DISPLAY INVISIBLE (3525 6800);
FORCEPROP 1 LAST VALUE 2K
J 2
(3875 6750);
DISPLAY 0.638298 (3875 6750);
FORCEPROP 1 LAST TOLERANCE 1%
J 0
(3925 6750);
DISPLAY 0.638298 (3925 6750);
FORCEPROP 1 LAST MATERIAL CHIP
J 0
(4025 6750);
DISPLAY 0.638298 (4025 6750);
FORCEPROP 1 LAST $LOCATION R3223
J 0
(3375 6750);
DISPLAY 0.638298 (3375 6750);
FORCEPROP 1 LASTPIN (3550 6750) $PN 1
J 0
(3562 6762);
DISPLAY 0.787234 (3562 6762);
FORCEPROP 1 LASTPIN (3750 6750) $PN 2
J 0
(3712 6762);
DISPLAY 0.787234 (3712 6762);
FORCEPROP 1 LAST PACK_TYPE 0402LF
J 0
(3525 6850);
DISPLAY 0.638298 (3525 6850);
DISPLAY INVISIBLE (3525 6850);
FORCEPROP 1 LAST WATTAGE 1/16W
J 2
(3950 6850);
DISPLAY 0.638298 (3950 6850);
DISPLAY INVISIBLE (3950 6850);
FORCEPROP 2 LAST CDS_LIB pure_quanta
J 0
(3650 6750);
PAINT MONO (3650 6750);
DISPLAY INVISIBLE (3650 6750);
FORCEPROP 1 LAST PATH I133
J 0
(3600 6900);
DISPLAY 0.978723 (3600 6900);
PAINT WHITE (3600 6900);
DISPLAY INVISIBLE (3600 6900);
FORCEPROP 2 LAST CDS_LOCATION R3223
J 0
(3600 6950);
DISPLAY 1.021277 (3600 6950);
DISPLAY INVISIBLE (3600 6950);
FORCEPROP 2 LAST $SEC 1
J 0
(3600 6950);
DISPLAY 0.680851 (3600 6950);
PAINT MONO (3600 6950);
DISPLAY INVISIBLE (3600 6950);
FORCEPROP 2 LAST CDS_SEC 1
J 0
(3600 6950);
DISPLAY 1.021277 (3600 6950);
DISPLAY INVISIBLE (3600 6950);
FORCEADD UNIVERSAL_POWER..1
(4200 7075);
FORCEPROP 3 LASTPIN (4200 7025) SIG_NAME P3V3_AUX\g
J 0
(4210 7035);
DISPLAY 0.659574 (4210 7035);
PAINT MONO (4210 7035);
DISPLAY INVISIBLE (4210 7035);
FORCEPROP 1 LAST HDL_POWER P3V3_AUX
J 1
(4200 7125);
DISPLAY 0.702128 (4200 7125);
PAINT GREEN (4200 7125);
FORCEPROP 2 LAST CDS_LIB logical_power
J 0
(4200 7075);
PAINT MONO (4200 7075);
DISPLAY INVISIBLE (4200 7075);
FORCEPROP 1 LAST PATH I138
J 0
(4250 7100);
DISPLAY 0.872340 (4250 7100);
PAINT AQUA (4250 7100);
DISPLAY INVISIBLE (4250 7100);
FORCEADD OFFPAGE..5
(2150 6450);
FORCEPROP 2 LAST $XR1 236 
J 0
(1806 6450);
DISPLAY 0.638298 (1806 6450);
PAINT MONO (1806 6450);
FORCEPROP 2 LAST $XR0 45 
J 0
(1926 6450);
DISPLAY 0.638298 (1926 6450);
PAINT MONO (1926 6450);
FORCEPROP 1 LAST OFFPAGE TRUE
J 0
(2475 6325);
DISPLAY 0.872340 (2475 6325);
PAINT GREEN (2475 6325);
DISPLAY INVISIBLE (2475 6325);
FORCEPROP 1 LAST COMMENT_BODY TRUE
J 0
(2250 6375);
DISPLAY 0.872340 (2250 6375);
PAINT PEACH (2250 6375);
DISPLAY INVISIBLE (2250 6375);
FORCEPROP 2 LAST CDS_LIB standard
J 0
(2150 6450);
PAINT MONO (2150 6450);
DISPLAY INVISIBLE (2150 6450);
FORCEPROP 2 LAST PATH I139
J 0
(1875 6500);
DISPLAY 1.021277 (1875 6500);
DISPLAY INVISIBLE (1875 6500);
FORCEADD Q_RES..2
(1350 4400);
FORCEPROP 1 LAST PART_NUMBER CS15602FB03
J 0
(1390 4225);
DISPLAY 0.510638 (1390 4225);
DISPLAY INVISIBLE (1390 4225);
FORCEPROP 1 LAST WATTAGE 1/16W
J 0
(1390 4375);
DISPLAY 0.510638 (1390 4375);
FORCEPROP 1 LAST TOLERANCE 1%
J 0
(1395 4425);
DISPLAY 0.510638 (1395 4425);
FORCEPROP 1 LAST VALUE 560
J 0
(1395 4475);
DISPLAY 0.510638 (1395 4475);
FORCEPROP 1 LAST PACK_TYPE 0402LF
J 0
(1390 4275);
DISPLAY 0.510638 (1390 4275);
FORCEPROP 1 LAST MATERIAL CHIP
J 0
(1390 4325);
DISPLAY 0.510638 (1390 4325);
FORCEPROP 1 LAST $LOCATION R980
J 0
(1395 4525);
DISPLAY 0.787234 (1395 4525);
FORCEPROP 1 LASTPIN (1350 4500) $PN 1
J 0
(1355 4462);
DISPLAY 0.787234 (1355 4462);
FORCEPROP 1 LASTPIN (1350 4300) $PN 2
J 0
(1355 4310);
DISPLAY 0.787234 (1355 4310);
FORCEPROP 1 LAST PATH I14
J 0
(1400 4575);
DISPLAY 0.978723 (1400 4575);
PAINT WHITE (1400 4575);
DISPLAY INVISIBLE (1400 4575);
FORCEPROP 2 LAST CDS_LIB pure_quanta
J 0
(1350 4400);
PAINT MONO (1350 4400);
DISPLAY INVISIBLE (1350 4400);
FORCEPROP 2 LAST CDS_LOCATION R980
J 0
(1400 4625);
DISPLAY 1.021277 (1400 4625);
DISPLAY INVISIBLE (1400 4625);
FORCEPROP 2 LAST $SEC 1
J 0
(1400 4625);
DISPLAY 0.680851 (1400 4625);
PAINT MONO (1400 4625);
DISPLAY INVISIBLE (1400 4625);
FORCEPROP 2 LAST CDS_SEC 1
J 0
(1400 4625);
DISPLAY 1.021277 (1400 4625);
DISPLAY INVISIBLE (1400 4625);
FORCEADD Q_RES..1
(-3175 5650);
FORCEPROP 1 LAST PART_NUMBER CS03322FB03
J 0
(-3300 5700);
DISPLAY 0.404255 (-3300 5700);
DISPLAY INVISIBLE (-3300 5700);
FORCEPROP 1 LAST VALUE 33.2
J 2
(-2975 5650);
DISPLAY 0.510638 (-2975 5650);
FORCEPROP 1 LAST TOLERANCE 1%
J 0
(-2950 5650);
DISPLAY 0.510638 (-2950 5650);
FORCEPROP 1 LAST MATERIAL CHIP
J 0
(-2875 5650);
DISPLAY 0.510638 (-2875 5650);
FORCEPROP 1 LAST LOCATION R994
J 0
(-3375 5650);
DISPLAY 0.638298 (-3375 5650);
FORCEPROP 1 LASTPIN (-3275 5650) $PN 1
J 0
(-3263 5662);
DISPLAY 0.787234 (-3263 5662);
PAINT MONO (-3263 5662);
FORCEPROP 1 LASTPIN (-3075 5650) $PN 2
J 0
(-3113 5662);
DISPLAY 0.787234 (-3113 5662);
PAINT MONO (-3113 5662);
FORCEPROP 1 LAST WATTAGE 1/16W
J 2
(-3075 5750);
DISPLAY 0.404255 (-3075 5750);
DISPLAY INVISIBLE (-3075 5750);
FORCEPROP 1 LAST PACK_TYPE 0402LF
J 0
(-3300 5750);
DISPLAY 0.404255 (-3300 5750);
DISPLAY INVISIBLE (-3300 5750);
FORCEPROP 1 LAST PATH I142
J 0
(-3225 5800);
DISPLAY 0.978723 (-3225 5800);
PAINT WHITE (-3225 5800);
DISPLAY INVISIBLE (-3225 5800);
FORCEPROP 2 LAST CDS_LIB pure_quanta
J 0
(-3175 5650);
DISPLAY INVISIBLE (-3175 5650);
FORCEPROP 0 LAST $SEC 1
J 0
(-3375 5700);
DISPLAY 0.680851 (-3375 5700);
PAINT MONO (-3375 5700);
DISPLAY INVISIBLE (-3375 5700);
FORCEPROP 0 LAST CDS_SEC 1
J 0
(-3375 5700);
DISPLAY 1.021277 (-3375 5700);
DISPLAY INVISIBLE (-3375 5700);
FORCEADD Q_RES..1
(-3175 3850);
FORCEPROP 1 LAST PART_NUMBER CS03322FB03
J 0
(-3300 3900);
DISPLAY 0.404255 (-3300 3900);
DISPLAY INVISIBLE (-3300 3900);
FORCEPROP 1 LAST MATERIAL CHIP
J 0
(-2875 3850);
DISPLAY 0.510638 (-2875 3850);
FORCEPROP 1 LAST TOLERANCE 1%
J 0
(-2950 3850);
DISPLAY 0.510638 (-2950 3850);
FORCEPROP 1 LAST VALUE 33.2
J 2
(-2975 3850);
DISPLAY 0.510638 (-2975 3850);
FORCEPROP 1 LAST LOCATION R996
J 0
(-3375 3850);
DISPLAY 0.638298 (-3375 3850);
FORCEPROP 1 LASTPIN (-3275 3850) $PN 1
J 0
(-3263 3862);
DISPLAY 0.787234 (-3263 3862);
PAINT MONO (-3263 3862);
FORCEPROP 1 LASTPIN (-3075 3850) $PN 2
J 0
(-3113 3862);
DISPLAY 0.787234 (-3113 3862);
PAINT MONO (-3113 3862);
FORCEPROP 1 LAST PACK_TYPE 0402LF
J 0
(-3300 3950);
DISPLAY 0.404255 (-3300 3950);
DISPLAY INVISIBLE (-3300 3950);
FORCEPROP 1 LAST WATTAGE 1/16W
J 2
(-3075 3950);
DISPLAY 0.404255 (-3075 3950);
DISPLAY INVISIBLE (-3075 3950);
FORCEPROP 1 LAST PATH I143
J 0
(-3225 4000);
DISPLAY 0.978723 (-3225 4000);
PAINT WHITE (-3225 4000);
DISPLAY INVISIBLE (-3225 4000);
FORCEPROP 2 LAST CDS_LIB pure_quanta
J 0
(-3175 3850);
DISPLAY INVISIBLE (-3175 3850);
FORCEPROP 0 LAST $SEC 1
J 0
(-3375 3900);
DISPLAY 0.680851 (-3375 3900);
PAINT MONO (-3375 3900);
DISPLAY INVISIBLE (-3375 3900);
FORCEPROP 0 LAST CDS_SEC 1
J 0
(-3375 3900);
DISPLAY 1.021277 (-3375 3900);
DISPLAY INVISIBLE (-3375 3900);
FORCEADD UNIVERSAL_POWER..1
(1150 4750);
FORCEPROP 3 LASTPIN (1150 4700) SIG_NAME P3V3_AUX\g
J 0
(1160 4710);
DISPLAY 0.659574 (1160 4710);
PAINT MONO (1160 4710);
DISPLAY INVISIBLE (1160 4710);
FORCEPROP 1 LAST HDL_POWER P3V3_AUX
J 1
(1150 4800);
DISPLAY 0.872340 (1150 4800);
PAINT GREEN (1150 4800);
FORCEPROP 2 LAST CDS_LIB logical_power
J 0
(1150 4750);
PAINT MONO (1150 4750);
DISPLAY INVISIBLE (1150 4750);
FORCEPROP 1 LAST PATH I15
J 0
(1200 4775);
DISPLAY 0.872340 (1200 4775);
PAINT AQUA (1200 4775);
DISPLAY INVISIBLE (1200 4775);
FORCEADD Q_RES..2
(1150 4400);
FORCEPROP 1 LAST PART_NUMBER CS15602FB03
J 0
(1190 4225);
DISPLAY 0.638298 (1190 4225);
DISPLAY INVISIBLE (1190 4225);
FORCEPROP 1 LAST TOLERANCE 1%
J 0
(1195 4425);
DISPLAY 0.510638 (1195 4425);
FORCEPROP 1 LAST PACK_TYPE 0402LF
J 0
(1190 4275);
DISPLAY 0.510638 (1190 4275);
FORCEPROP 1 LAST VALUE 560
J 0
(1195 4475);
DISPLAY 0.510638 (1195 4475);
FORCEPROP 1 LAST MATERIAL CHIP
J 0
(1190 4325);
DISPLAY 0.510638 (1190 4325);
FORCEPROP 1 LAST WATTAGE 1/16W
J 0
(1190 4375);
DISPLAY 0.510638 (1190 4375);
FORCEPROP 1 LAST $LOCATION R978
J 0
(1195 4525);
DISPLAY 0.787234 (1195 4525);
FORCEPROP 1 LASTPIN (1150 4500) $PN 1
J 0
(1155 4462);
DISPLAY 0.787234 (1155 4462);
FORCEPROP 1 LASTPIN (1150 4300) $PN 2
J 0
(1155 4310);
DISPLAY 0.787234 (1155 4310);
FORCEPROP 1 LAST PATH I16
J 0
(1200 4575);
DISPLAY 0.978723 (1200 4575);
PAINT WHITE (1200 4575);
DISPLAY INVISIBLE (1200 4575);
FORCEPROP 2 LAST CDS_LIB pure_quanta
J 0
(1150 4400);
PAINT MONO (1150 4400);
DISPLAY INVISIBLE (1150 4400);
FORCEPROP 2 LAST CDS_LOCATION R978
J 0
(1200 4625);
DISPLAY 1.021277 (1200 4625);
DISPLAY INVISIBLE (1200 4625);
FORCEPROP 2 LAST $SEC 1
J 0
(1200 4625);
DISPLAY 0.680851 (1200 4625);
PAINT MONO (1200 4625);
DISPLAY INVISIBLE (1200 4625);
FORCEPROP 2 LAST CDS_SEC 1
J 0
(1200 4625);
DISPLAY 1.021277 (1200 4625);
DISPLAY INVISIBLE (1200 4625);
FORCEADD OFFPAGE..3
(2175 5650);
FORCEPROP 2 LAST $XR0 236 
J 0
(2389 5650);
DISPLAY 0.638298 (2389 5650);
PAINT MONO (2389 5650);
FORCEPROP 2 LAST PATH I2
J 0
(2400 5700);
DISPLAY 1.021277 (2400 5700);
DISPLAY INVISIBLE (2400 5700);
FORCEPROP 2 LAST CDS_LIB standard
J 0
(2175 5650);
PAINT MONO (2175 5650);
DISPLAY INVISIBLE (2175 5650);
FORCEPROP 1 LAST OFFPAGE TRUE
J 0
(2500 5525);
DISPLAY 0.872340 (2500 5525);
PAINT GREEN (2500 5525);
DISPLAY INVISIBLE (2500 5525);
FORCEPROP 1 LAST COMMENT_BODY TRUE
J 0
(2125 5550);
DISPLAY 0.872340 (2125 5550);
PAINT GREEN (2125 5550);
DISPLAY INVISIBLE (2125 5550);
FORCEADD UNIVERSAL_POWER..1
(-475 6550);
FORCEPROP 3 LASTPIN (-475 6500) SIG_NAME P3V3_AUX\g
J 0
(-465 6510);
DISPLAY 0.659574 (-465 6510);
PAINT MONO (-465 6510);
DISPLAY INVISIBLE (-465 6510);
FORCEPROP 1 LAST HDL_POWER P3V3_AUX
J 1
(-475 6600);
DISPLAY 0.872340 (-475 6600);
PAINT GREEN (-475 6600);
FORCEPROP 2 LAST CDS_LIB logical_power
J 0
(-475 6550);
PAINT MONO (-475 6550);
DISPLAY INVISIBLE (-475 6550);
FORCEPROP 1 LAST PATH I21
J 0
(-425 6575);
DISPLAY 0.872340 (-425 6575);
PAINT AQUA (-425 6575);
DISPLAY INVISIBLE (-425 6575);
FORCEADD Q_CAP..1
(-475 6225);
FORCEPROP 1 LAST PART_NUMBER CH4104K1B00
J 0
(-425 6075);
DISPLAY 0.510638 (-425 6075);
DISPLAY INVISIBLE (-425 6075);
FORCEPROP 1 LAST PACK_TYPE 0402
J 0
(-425 6025);
DISPLAY 0.510638 (-425 6025);
FORCEPROP 1 LAST VALUE 0.1UF
J 0
(-425 6275);
DISPLAY 0.510638 (-425 6275);
FORCEPROP 1 LAST MATERIAL X7R
J 0
(-425 6125);
DISPLAY 0.510638 (-425 6125);
FORCEPROP 1 LAST VOLTAGE 25V
J 0
(-425 6225);
DISPLAY 0.510638 (-425 6225);
FORCEPROP 1 LAST TOLERANCE 10%
J 0
(-425 6175);
DISPLAY 0.510638 (-425 6175);
FORCEPROP 1 LAST $LOCATION C569
J 0
(-425 6325);
DISPLAY 0.787234 (-425 6325);
FORCEPROP 1 LASTPIN (-475 6325) $PN 1
J 0
(-465 6305);
DISPLAY 0.787234 (-465 6305);
FORCEPROP 1 LASTPIN (-475 6125) $PN 2
J 0
(-465 6105);
DISPLAY 0.787234 (-465 6105);
FORCEPROP 1 LAST PATH I22
J 0
(-425 6375);
DISPLAY 0.978723 (-425 6375);
PAINT WHITE (-425 6375);
DISPLAY INVISIBLE (-425 6375);
FORCEPROP 2 LAST CDS_LIB pure_quanta
J 2
(-475 6225);
PAINT MONO (-475 6225);
DISPLAY INVISIBLE (-475 6225);
FORCEPROP 1 LAST $LOCATION C569
J 0
(-425 6425);
DISPLAY 1.021277 (-425 6425);
DISPLAY INVISIBLE (-425 6425);
FORCEPROP 2 LAST CDS_LOCATION C569
J 0
(-425 6425);
DISPLAY 1.021277 (-425 6425);
DISPLAY INVISIBLE (-425 6425);
FORCEPROP 2 LAST $SEC 1
J 0
(-425 6425);
DISPLAY 0.680851 (-425 6425);
PAINT MONO (-425 6425);
DISPLAY INVISIBLE (-425 6425);
FORCEPROP 2 LAST CDS_SEC 1
J 0
(-425 6425);
DISPLAY 1.021277 (-425 6425);
DISPLAY INVISIBLE (-425 6425);
FORCEADD UNIVERSAL_GND..1
(-475 6000);
FORCEPROP 3 LASTPIN (-475 6050) SIG_NAME GND\g
J 0
(-465 6060);
DISPLAY 0.659574 (-465 6060);
PAINT MONO (-465 6060);
DISPLAY INVISIBLE (-465 6060);
FORCEPROP 1 LAST PATH I23
J 0
(-400 6000);
DISPLAY 0.872340 (-400 6000);
PAINT AQUA (-400 6000);
DISPLAY INVISIBLE (-400 6000);
FORCEPROP 2 LAST CDS_LIB logical_power
J 0
(-475 6000);
PAINT MONO (-475 6000);
DISPLAY INVISIBLE (-475 6000);
FORCEPROP 1 LAST HDL_POWER GND
J 1
(-450 5925);
DISPLAY 0.872340 (-450 5925);
PAINT GREEN (-450 5925);
DISPLAY INVISIBLE (-450 5925);
FORCEADD UNIVERSAL_POWER..1
(-1825 6550);
FORCEPROP 3 LASTPIN (-1825 6500) SIG_NAME PVNN_TERM_CPU0\g
J 0
(-1815 6510);
DISPLAY 0.659574 (-1815 6510);
PAINT MONO (-1815 6510);
DISPLAY INVISIBLE (-1815 6510);
FORCEPROP 1 LAST HDL_POWER PVNN_TERM_CPU0
J 1
(-1825 6600);
DISPLAY 0.872340 (-1825 6600);
PAINT GREEN (-1825 6600);
FORCEPROP 2 LAST CDS_LIB logical_power
J 0
(-1825 6550);
PAINT MONO (-1825 6550);
DISPLAY INVISIBLE (-1825 6550);
FORCEPROP 1 LAST PATH I24
J 0
(-1775 6575);
DISPLAY 0.872340 (-1775 6575);
PAINT AQUA (-1775 6575);
DISPLAY INVISIBLE (-1775 6575);
FORCEADD Q_CAP..1
R 2
(-1825 6225);
FORCEPROP 1 LAST PART_NUMBER CH4104K1B00
J 2
(-1875 6075);
DISPLAY 0.510638 (-1875 6075);
DISPLAY INVISIBLE (-1875 6075);
FORCEPROP 1 LAST VALUE 0.1UF
J 2
(-1875 6275);
DISPLAY 0.510638 (-1875 6275);
FORCEPROP 1 LAST PACK_TYPE 0402
J 2
(-1875 6025);
DISPLAY 0.510638 (-1875 6025);
FORCEPROP 1 LAST MATERIAL X7R
J 2
(-1875 6125);
DISPLAY 0.510638 (-1875 6125);
FORCEPROP 1 LAST VOLTAGE 25V
J 2
(-1875 6225);
DISPLAY 0.510638 (-1875 6225);
FORCEPROP 1 LAST TOLERANCE 10%
J 2
(-1875 6175);
DISPLAY 0.510638 (-1875 6175);
FORCEPROP 1 LAST $LOCATION C567
J 2
(-1875 6325);
DISPLAY 0.787234 (-1875 6325);
FORCEPROP 1 LASTPIN (-1825 6325) $PN 1
J 2
(-1835 6305);
DISPLAY 0.787234 (-1835 6305);
FORCEPROP 1 LASTPIN (-1825 6125) $PN 2
J 2
(-1835 6105);
DISPLAY 0.787234 (-1835 6105);
FORCEPROP 2 LAST CDS_LIB pure_quanta
J 2
(-1825 6225);
PAINT MONO (-1825 6225);
DISPLAY INVISIBLE (-1825 6225);
FORCEPROP 1 LAST PATH I25
J 2
(-1875 6375);
DISPLAY 0.978723 (-1875 6375);
PAINT WHITE (-1875 6375);
DISPLAY INVISIBLE (-1875 6375);
FORCEPROP 1 LAST $LOCATION C567
J 0
(-1875 6425);
DISPLAY 1.021277 (-1875 6425);
DISPLAY INVISIBLE (-1875 6425);
FORCEPROP 2 LAST CDS_LOCATION C567
J 0
(-1875 6425);
DISPLAY 1.021277 (-1875 6425);
DISPLAY INVISIBLE (-1875 6425);
FORCEPROP 2 LAST $SEC 1
J 0
(-1875 6425);
DISPLAY 0.680851 (-1875 6425);
PAINT MONO (-1875 6425);
DISPLAY INVISIBLE (-1875 6425);
FORCEPROP 2 LAST CDS_SEC 1
J 0
(-1875 6425);
DISPLAY 1.021277 (-1875 6425);
DISPLAY INVISIBLE (-1875 6425);
FORCEADD UNIVERSAL_GND..1
(-1825 6000);
FORCEPROP 3 LASTPIN (-1825 6050) SIG_NAME GND\g
J 0
(-1815 6060);
DISPLAY 0.659574 (-1815 6060);
PAINT MONO (-1815 6060);
DISPLAY INVISIBLE (-1815 6060);
FORCEPROP 1 LAST HDL_POWER GND
J 1
(-1800 5925);
DISPLAY 0.872340 (-1800 5925);
PAINT GREEN (-1800 5925);
DISPLAY INVISIBLE (-1800 5925);
FORCEPROP 2 LAST CDS_LIB logical_power
J 0
(-1825 6000);
PAINT MONO (-1825 6000);
DISPLAY INVISIBLE (-1825 6000);
FORCEPROP 1 LAST PATH I26
J 0
(-1750 6000);
DISPLAY 0.872340 (-1750 6000);
PAINT AQUA (-1750 6000);
DISPLAY INVISIBLE (-1750 6000);
FORCEADD PCA9517AD..1
(-1125 5700);
FORCEPROP 1 LAST PART_NUMBER AL009517000
J 0
(-1400 6075);
DISPLAY 0.723404 (-1400 6075);
PAINT GREEN (-1400 6075);
DISPLAY INVISIBLE (-1400 6075);
FORCEPROP 2 LAST VALUE PCA9517AD
J 0
(-1375 6200);
DISPLAY 1.021277 (-1375 6200);
FORCEPROP 2 LAST PART_TYPE SMLF
J 0
(-1375 6250);
DISPLAY 1.021277 (-1375 6250);
FORCEPROP 1 LAST MATERIAL IC
J 0
(-1400 6025);
DISPLAY 0.723404 (-1400 6025);
PAINT GREEN (-1400 6025);
FORCEPROP 1 LAST $LOCATION U30
J 0
(-1400 6125);
DISPLAY 0.723404 (-1400 6125);
PAINT GREEN (-1400 6125);
FORCEPROP 0 LASTPIN (-700 5500) $PN 5
J 0
(-690 5510);
DISPLAY 0.680851 (-690 5510);
PAINT MONO (-690 5510);
FORCEPROP 0 LASTPIN (-1550 5500) $PN 4
J 2
(-1560 5510);
DISPLAY 0.680851 (-1560 5510);
PAINT MONO (-1560 5510);
FORCEPROP 0 LASTPIN (-1550 5750) $PN 2
J 2
(-1560 5760);
DISPLAY 0.680851 (-1560 5760);
PAINT MONO (-1560 5760);
FORCEPROP 0 LASTPIN (-700 5750) $PN 7
J 0
(-690 5760);
DISPLAY 0.680851 (-690 5760);
PAINT MONO (-690 5760);
FORCEPROP 0 LASTPIN (-1550 5650) $PN 3
J 2
(-1560 5660);
DISPLAY 0.680851 (-1560 5660);
PAINT MONO (-1560 5660);
FORCEPROP 0 LASTPIN (-700 5650) $PN 6
J 0
(-690 5660);
DISPLAY 0.680851 (-690 5660);
PAINT MONO (-690 5660);
FORCEPROP 0 LASTPIN (-1550 5900) $PN 1
J 2
(-1560 5910);
DISPLAY 0.680851 (-1560 5910);
PAINT MONO (-1560 5910);
FORCEPROP 0 LASTPIN (-700 5900) $PN 8
J 0
(-690 5910);
DISPLAY 0.680851 (-690 5910);
PAINT MONO (-690 5910);
FORCEPROP 2 LAST CDS_LIB pure_quanta
J 0
(-1125 5700);
DISPLAY INVISIBLE (-1125 5700);
FORCEPROP 1 LAST PATH I28
J 0
(-875 6025);
DISPLAY 0.723404 (-875 6025);
PAINT GREEN (-875 6025);
DISPLAY INVISIBLE (-875 6025);
FORCEPROP 1 LAST NEEDS_NO_SIZE TRUE
J 0
(-1125 5700);
DISPLAY 0.468085 (-1125 5700);
PAINT GREEN (-1125 5700);
DISPLAY INVISIBLE (-1125 5700);
FORCEPROP 2 LAST CDS_LOCATION U30
J 0
(-1375 6250);
DISPLAY 1.021277 (-1375 6250);
DISPLAY INVISIBLE (-1375 6250);
FORCEPROP 0 LAST $SEC 1
J 0
(-1375 6300);
DISPLAY 0.680851 (-1375 6300);
PAINT MONO (-1375 6300);
DISPLAY INVISIBLE (-1375 6300);
FORCEPROP 0 LAST CDS_SEC 1
J 0
(-1375 6300);
DISPLAY 1.021277 (-1375 6300);
DISPLAY INVISIBLE (-1375 6300);
FORCEADD UNIVERSAL_GND..1
(-1675 5350);
FORCEPROP 3 LASTPIN (-1675 5400) SIG_NAME GND\g
J 0
(-1665 5410);
DISPLAY 0.659574 (-1665 5410);
PAINT MONO (-1665 5410);
DISPLAY INVISIBLE (-1665 5410);
FORCEPROP 1 LAST HDL_POWER GND
J 1
(-1650 5275);
DISPLAY 0.872340 (-1650 5275);
PAINT GREEN (-1650 5275);
DISPLAY INVISIBLE (-1650 5275);
FORCEPROP 2 LAST CDS_LIB logical_power
J 0
(-1675 5350);
PAINT MONO (-1675 5350);
DISPLAY INVISIBLE (-1675 5350);
FORCEPROP 1 LAST PATH I29
J 0
(-1600 5350);
DISPLAY 0.872340 (-1600 5350);
PAINT AQUA (-1600 5350);
DISPLAY INVISIBLE (-1600 5350);
FORCEADD Q_RES..2
(2000 4800);
FORCEPROP 1 LAST PART_NUMBER CS00002JB13
J 0
(2040 4625);
DISPLAY 0.638298 (2040 4625);
DISPLAY INVISIBLE (2040 4625);
FORCEPROP 1 LAST TOLERANCE 5%
J 0
(2045 4825);
DISPLAY 0.638298 (2045 4825);
FORCEPROP 1 LAST MATERIAL EMPTY
J 0
(2040 4725);
DISPLAY 0.638298 (2040 4725);
PAINT RED (2040 4725);
FORCEPROP 1 LAST VALUE 0
J 0
(2045 4875);
DISPLAY 0.638298 (2045 4875);
FORCEPROP 1 LAST WATTAGE 1/16W
J 0
(2040 4775);
DISPLAY 0.638298 (2040 4775);
FORCEPROP 1 LAST PACK_TYPE 0402LF
J 0
(2040 4675);
DISPLAY 0.638298 (2040 4675);
FORCEPROP 1 LAST $LOCATION R1648
J 0
(2045 4925);
DISPLAY 0.638298 (2045 4925);
FORCEPROP 1 LASTPIN (2000 4900) $PN 1
J 0
(2005 4862);
DISPLAY 0.787234 (2005 4862);
FORCEPROP 1 LASTPIN (2000 4700) $PN 2
J 0
(2005 4710);
DISPLAY 0.787234 (2005 4710);
FORCEPROP 1 LAST PATH I3
J 0
(2050 4975);
DISPLAY 0.978723 (2050 4975);
PAINT WHITE (2050 4975);
DISPLAY INVISIBLE (2050 4975);
FORCEPROP 2 LAST CDS_LIB pure_quanta
J 0
(2000 4800);
PAINT MONO (2000 4800);
DISPLAY INVISIBLE (2000 4800);
FORCEPROP 2 LAST CDS_LOCATION R1648
J 0
(2050 5025);
DISPLAY 1.021277 (2050 5025);
DISPLAY INVISIBLE (2050 5025);
FORCEPROP 2 LAST $SEC 1
J 0
(2050 5025);
DISPLAY 0.680851 (2050 5025);
PAINT MONO (2050 5025);
DISPLAY INVISIBLE (2050 5025);
FORCEPROP 2 LAST CDS_SEC 1
J 0
(2050 5025);
DISPLAY 1.021277 (2050 5025);
DISPLAY INVISIBLE (2050 5025);
FORCEADD UNIVERSAL_POWER..1
(-475 4750);
FORCEPROP 3 LASTPIN (-475 4700) SIG_NAME P3V3_AUX\g
J 0
(-465 4710);
DISPLAY 0.659574 (-465 4710);
PAINT MONO (-465 4710);
DISPLAY INVISIBLE (-465 4710);
FORCEPROP 1 LAST HDL_POWER P3V3_AUX
J 1
(-475 4800);
DISPLAY 0.872340 (-475 4800);
PAINT GREEN (-475 4800);
FORCEPROP 2 LAST CDS_LIB logical_power
J 0
(-475 4750);
PAINT MONO (-475 4750);
DISPLAY INVISIBLE (-475 4750);
FORCEPROP 1 LAST PATH I31
J 0
(-425 4775);
DISPLAY 0.872340 (-425 4775);
PAINT AQUA (-425 4775);
DISPLAY INVISIBLE (-425 4775);
FORCEADD UNIVERSAL_GND..1
(-475 4200);
FORCEPROP 3 LASTPIN (-475 4250) SIG_NAME GND\g
J 0
(-465 4260);
DISPLAY 0.659574 (-465 4260);
PAINT MONO (-465 4260);
DISPLAY INVISIBLE (-465 4260);
FORCEPROP 2 LAST CDS_LIB logical_power
J 0
(-475 4200);
PAINT MONO (-475 4200);
DISPLAY INVISIBLE (-475 4200);
FORCEPROP 1 LAST HDL_POWER GND
J 1
(-450 4125);
DISPLAY 0.872340 (-450 4125);
PAINT GREEN (-450 4125);
DISPLAY INVISIBLE (-450 4125);
FORCEPROP 1 LAST PATH I32
J 0
(-400 4200);
DISPLAY 0.872340 (-400 4200);
PAINT AQUA (-400 4200);
DISPLAY INVISIBLE (-400 4200);
FORCEADD Q_CAP..1
(-475 4425);
FORCEPROP 1 LAST PART_NUMBER CH4104K1B00
J 0
(-425 4275);
DISPLAY 0.510638 (-425 4275);
DISPLAY INVISIBLE (-425 4275);
FORCEPROP 1 LAST VOLTAGE 25V
J 0
(-425 4425);
DISPLAY 0.510638 (-425 4425);
FORCEPROP 1 LAST TOLERANCE 10%
J 0
(-425 4375);
DISPLAY 0.510638 (-425 4375);
FORCEPROP 1 LAST VALUE 0.1UF
J 0
(-425 4475);
DISPLAY 0.510638 (-425 4475);
FORCEPROP 1 LAST PACK_TYPE 0402
J 0
(-425 4225);
DISPLAY 0.510638 (-425 4225);
FORCEPROP 1 LAST MATERIAL X7R
J 0
(-425 4325);
DISPLAY 0.510638 (-425 4325);
FORCEPROP 1 LAST $LOCATION C570
J 0
(-425 4525);
DISPLAY 0.787234 (-425 4525);
FORCEPROP 1 LASTPIN (-475 4525) $PN 1
J 0
(-465 4505);
DISPLAY 0.787234 (-465 4505);
FORCEPROP 1 LASTPIN (-475 4325) $PN 2
J 0
(-465 4305);
DISPLAY 0.787234 (-465 4305);
FORCEPROP 2 LAST CDS_LIB pure_quanta
J 2
(-475 4425);
PAINT MONO (-475 4425);
DISPLAY INVISIBLE (-475 4425);
FORCEPROP 1 LAST PATH I33
J 0
(-425 4575);
DISPLAY 0.978723 (-425 4575);
PAINT WHITE (-425 4575);
DISPLAY INVISIBLE (-425 4575);
FORCEPROP 1 LAST $LOCATION C570
J 0
(-425 4625);
DISPLAY 1.021277 (-425 4625);
DISPLAY INVISIBLE (-425 4625);
FORCEPROP 2 LAST CDS_LOCATION C570
J 0
(-425 4625);
DISPLAY 1.021277 (-425 4625);
DISPLAY INVISIBLE (-425 4625);
FORCEPROP 2 LAST $SEC 1
J 0
(-425 4625);
DISPLAY 0.680851 (-425 4625);
PAINT MONO (-425 4625);
DISPLAY INVISIBLE (-425 4625);
FORCEPROP 2 LAST CDS_SEC 1
J 0
(-425 4625);
DISPLAY 1.021277 (-425 4625);
DISPLAY INVISIBLE (-425 4625);
FORCEADD UNIVERSAL_POWER..1
(-1825 4750);
FORCEPROP 3 LASTPIN (-1825 4700) SIG_NAME PVNN_TERM_CPU1\g
J 0
(-1815 4710);
DISPLAY 0.659574 (-1815 4710);
PAINT MONO (-1815 4710);
DISPLAY INVISIBLE (-1815 4710);
FORCEPROP 1 LAST HDL_POWER PVNN_TERM_CPU1
J 1
(-1825 4800);
DISPLAY 0.872340 (-1825 4800);
PAINT GREEN (-1825 4800);
FORCEPROP 2 LAST CDS_LIB logical_power
J 0
(-1825 4750);
PAINT MONO (-1825 4750);
DISPLAY INVISIBLE (-1825 4750);
FORCEPROP 1 LAST PATH I34
J 0
(-1775 4775);
DISPLAY 0.872340 (-1775 4775);
PAINT AQUA (-1775 4775);
DISPLAY INVISIBLE (-1775 4775);
FORCEADD Q_CAP..1
R 2
(-1825 4425);
FORCEPROP 1 LAST PART_NUMBER CH4104K1B00
J 2
(-1875 4275);
DISPLAY 0.510638 (-1875 4275);
DISPLAY INVISIBLE (-1875 4275);
FORCEPROP 1 LAST VALUE 0.1UF
J 2
(-1875 4475);
DISPLAY 0.510638 (-1875 4475);
FORCEPROP 1 LAST VOLTAGE 25V
J 2
(-1875 4425);
DISPLAY 0.510638 (-1875 4425);
FORCEPROP 1 LAST TOLERANCE 10%
J 2
(-1875 4375);
DISPLAY 0.510638 (-1875 4375);
FORCEPROP 1 LAST MATERIAL X7R
J 2
(-1875 4325);
DISPLAY 0.510638 (-1875 4325);
FORCEPROP 1 LAST PACK_TYPE 0402
J 2
(-1875 4225);
DISPLAY 0.510638 (-1875 4225);
FORCEPROP 1 LAST $LOCATION C568
J 2
(-1875 4525);
DISPLAY 0.787234 (-1875 4525);
FORCEPROP 1 LASTPIN (-1825 4525) $PN 1
J 2
(-1835 4505);
DISPLAY 0.787234 (-1835 4505);
FORCEPROP 1 LASTPIN (-1825 4325) $PN 2
J 2
(-1835 4305);
DISPLAY 0.787234 (-1835 4305);
FORCEPROP 2 LAST CDS_LIB pure_quanta
J 2
(-1825 4425);
PAINT MONO (-1825 4425);
DISPLAY INVISIBLE (-1825 4425);
FORCEPROP 1 LAST PATH I35
J 2
(-1875 4575);
DISPLAY 0.978723 (-1875 4575);
PAINT WHITE (-1875 4575);
DISPLAY INVISIBLE (-1875 4575);
FORCEPROP 1 LAST $LOCATION C568
J 0
(-1875 4625);
DISPLAY 1.021277 (-1875 4625);
DISPLAY INVISIBLE (-1875 4625);
FORCEPROP 2 LAST CDS_LOCATION C568
J 0
(-1875 4625);
DISPLAY 1.021277 (-1875 4625);
DISPLAY INVISIBLE (-1875 4625);
FORCEPROP 2 LAST $SEC 1
J 0
(-1875 4625);
DISPLAY 0.680851 (-1875 4625);
PAINT MONO (-1875 4625);
DISPLAY INVISIBLE (-1875 4625);
FORCEPROP 2 LAST CDS_SEC 1
J 0
(-1875 4625);
DISPLAY 1.021277 (-1875 4625);
DISPLAY INVISIBLE (-1875 4625);
FORCEADD UNIVERSAL_GND..1
(-1825 4200);
FORCEPROP 3 LASTPIN (-1825 4250) SIG_NAME GND\g
J 0
(-1815 4260);
DISPLAY 0.659574 (-1815 4260);
PAINT MONO (-1815 4260);
DISPLAY INVISIBLE (-1815 4260);
FORCEPROP 2 LAST CDS_LIB logical_power
J 0
(-1825 4200);
PAINT MONO (-1825 4200);
DISPLAY INVISIBLE (-1825 4200);
FORCEPROP 1 LAST HDL_POWER GND
J 1
(-1800 4125);
DISPLAY 0.872340 (-1800 4125);
PAINT GREEN (-1800 4125);
DISPLAY INVISIBLE (-1800 4125);
FORCEPROP 1 LAST PATH I36
J 0
(-1750 4200);
DISPLAY 0.872340 (-1750 4200);
PAINT AQUA (-1750 4200);
DISPLAY INVISIBLE (-1750 4200);
FORCEADD PCA9517AD..1
(-1125 3900);
FORCEPROP 1 LAST PART_NUMBER AL009517000
J 0
(-1400 4275);
DISPLAY 0.723404 (-1400 4275);
PAINT GREEN (-1400 4275);
DISPLAY INVISIBLE (-1400 4275);
FORCEPROP 1 LAST MATERIAL IC
J 0
(-1400 4225);
DISPLAY 0.723404 (-1400 4225);
PAINT GREEN (-1400 4225);
FORCEPROP 2 LAST PART_TYPE SMLF
J 0
(-1375 4450);
DISPLAY 1.021277 (-1375 4450);
FORCEPROP 2 LAST VALUE PCA9517AD
J 0
(-1375 4400);
DISPLAY 1.021277 (-1375 4400);
FORCEPROP 1 LAST $LOCATION U31
J 0
(-1400 4325);
DISPLAY 0.723404 (-1400 4325);
PAINT GREEN (-1400 4325);
FORCEPROP 0 LASTPIN (-700 3700) $PN 5
J 0
(-690 3710);
DISPLAY 0.680851 (-690 3710);
PAINT MONO (-690 3710);
FORCEPROP 0 LASTPIN (-1550 3700) $PN 4
J 2
(-1560 3710);
DISPLAY 0.680851 (-1560 3710);
PAINT MONO (-1560 3710);
FORCEPROP 0 LASTPIN (-1550 3950) $PN 2
J 2
(-1560 3960);
DISPLAY 0.680851 (-1560 3960);
PAINT MONO (-1560 3960);
FORCEPROP 0 LASTPIN (-700 3950) $PN 7
J 0
(-690 3960);
DISPLAY 0.680851 (-690 3960);
PAINT MONO (-690 3960);
FORCEPROP 0 LASTPIN (-1550 3850) $PN 3
J 2
(-1560 3860);
DISPLAY 0.680851 (-1560 3860);
PAINT MONO (-1560 3860);
FORCEPROP 0 LASTPIN (-700 3850) $PN 6
J 0
(-690 3860);
DISPLAY 0.680851 (-690 3860);
PAINT MONO (-690 3860);
FORCEPROP 0 LASTPIN (-1550 4100) $PN 1
J 2
(-1560 4110);
DISPLAY 0.680851 (-1560 4110);
PAINT MONO (-1560 4110);
FORCEPROP 0 LASTPIN (-700 4100) $PN 8
J 0
(-690 4110);
DISPLAY 0.680851 (-690 4110);
PAINT MONO (-690 4110);
FORCEPROP 2 LAST CDS_LIB pure_quanta
J 0
(-1125 3900);
DISPLAY INVISIBLE (-1125 3900);
FORCEPROP 1 LAST PATH I37
J 0
(-875 4225);
DISPLAY 0.723404 (-875 4225);
PAINT GREEN (-875 4225);
DISPLAY INVISIBLE (-875 4225);
FORCEPROP 1 LAST NEEDS_NO_SIZE TRUE
J 0
(-1125 3900);
DISPLAY 0.468085 (-1125 3900);
PAINT GREEN (-1125 3900);
DISPLAY INVISIBLE (-1125 3900);
FORCEPROP 2 LAST CDS_LOCATION U31
J 0
(-1375 4450);
DISPLAY 1.021277 (-1375 4450);
DISPLAY INVISIBLE (-1375 4450);
FORCEPROP 0 LAST $SEC 1
J 0
(-1375 4500);
DISPLAY 0.680851 (-1375 4500);
PAINT MONO (-1375 4500);
DISPLAY INVISIBLE (-1375 4500);
FORCEPROP 0 LAST CDS_SEC 1
J 0
(-1375 4500);
DISPLAY 1.021277 (-1375 4500);
DISPLAY INVISIBLE (-1375 4500);
FORCEADD UNIVERSAL_GND..1
(-1675 3550);
FORCEPROP 3 LASTPIN (-1675 3600) SIG_NAME GND\g
J 0
(-1665 3610);
DISPLAY 0.659574 (-1665 3610);
PAINT MONO (-1665 3610);
DISPLAY INVISIBLE (-1665 3610);
FORCEPROP 2 LAST CDS_LIB logical_power
J 0
(-1675 3550);
PAINT MONO (-1675 3550);
DISPLAY INVISIBLE (-1675 3550);
FORCEPROP 1 LAST HDL_POWER GND
J 1
(-1650 3475);
DISPLAY 0.872340 (-1650 3475);
PAINT GREEN (-1650 3475);
DISPLAY INVISIBLE (-1650 3475);
FORCEPROP 1 LAST PATH I38
J 0
(-1600 3550);
DISPLAY 0.872340 (-1600 3550);
PAINT AQUA (-1600 3550);
DISPLAY INVISIBLE (-1600 3550);
FORCEADD OFFPAGE..4
(2175 3950);
FORCEPROP 2 LAST $XR0 236 
J 0
(2361 3950);
DISPLAY 0.638298 (2361 3950);
PAINT MONO (2361 3950);
FORCEPROP 2 LAST CDS_LIB standard
J 0
(2175 3950);
PAINT MONO (2175 3950);
DISPLAY INVISIBLE (2175 3950);
FORCEPROP 2 LAST PATH I4
J 0
(2375 4000);
DISPLAY 1.021277 (2375 4000);
DISPLAY INVISIBLE (2375 4000);
FORCEPROP 1 LAST OFFPAGE TRUE
J 0
(2500 3825);
DISPLAY 0.872340 (2500 3825);
DISPLAY INVISIBLE (2500 3825);
FORCEPROP 1 LAST COMMENT_BODY TRUE
J 0
(2150 3850);
DISPLAY 0.872340 (2150 3850);
PAINT GREEN (2150 3850);
DISPLAY INVISIBLE (2150 3850);
FORCEADD UNIVERSAL_POWER..1
(-2725 6550);
FORCEPROP 3 LASTPIN (-2725 6500) SIG_NAME PVNN_TERM_CPU0\g
J 0
(-2715 6510);
DISPLAY 0.659574 (-2715 6510);
PAINT MONO (-2715 6510);
DISPLAY INVISIBLE (-2715 6510);
FORCEPROP 1 LAST HDL_POWER PVNN_TERM_CPU0
J 1
(-2725 6600);
DISPLAY 0.872340 (-2725 6600);
PAINT GREEN (-2725 6600);
FORCEPROP 1 LAST PATH I41
J 0
(-2675 6575);
DISPLAY 0.872340 (-2675 6575);
PAINT AQUA (-2675 6575);
DISPLAY INVISIBLE (-2675 6575);
FORCEPROP 2 LAST CDS_LIB logical_power
J 0
(-2725 6550);
PAINT MONO (-2725 6550);
DISPLAY INVISIBLE (-2725 6550);
FORCEADD Q_RES..2
R 2
(-2500 6200);
FORCEPROP 1 LAST PART_NUMBER CS12402FB01
J 2
(-2540 6075);
DISPLAY 0.510638 (-2540 6075);
DISPLAY INVISIBLE (-2540 6075);
FORCEPROP 1 LAST WATTAGE 1/16W
J 2
(-2540 6175);
DISPLAY 0.510638 (-2540 6175);
FORCEPROP 1 LAST PACK_TYPE 0402LF
J 2
(-2540 6075);
DISPLAY 0.510638 (-2540 6075);
FORCEPROP 1 LAST MATERIAL CHIP
J 2
(-2540 6125);
DISPLAY 0.510638 (-2540 6125);
FORCEPROP 1 LAST VALUE 240
J 2
(-2545 6275);
DISPLAY 0.510638 (-2545 6275);
FORCEPROP 1 LAST TOLERANCE 1%
J 2
(-2545 6225);
DISPLAY 0.510638 (-2545 6225);
FORCEPROP 1 LAST $LOCATION R971
J 2
(-2520 6325);
DISPLAY 0.787234 (-2520 6325);
FORCEPROP 1 LASTPIN (-2500 6300) $PN 1
J 2
(-2505 6262);
DISPLAY 0.787234 (-2505 6262);
FORCEPROP 1 LASTPIN (-2500 6100) $PN 2
J 2
(-2505 6110);
DISPLAY 0.787234 (-2505 6110);
FORCEPROP 1 LAST PATH I42
J 2
(-2550 6375);
DISPLAY 0.978723 (-2550 6375);
PAINT WHITE (-2550 6375);
DISPLAY INVISIBLE (-2550 6375);
FORCEPROP 2 LAST CDS_LIB pure_quanta
J 0
(-2500 6200);
PAINT MONO (-2500 6200);
DISPLAY INVISIBLE (-2500 6200);
FORCEPROP 1 LAST $LOCATION R971
J 0
(-2550 6425);
DISPLAY 1.021277 (-2550 6425);
DISPLAY INVISIBLE (-2550 6425);
FORCEPROP 2 LAST CDS_LOCATION R971
J 0
(-2550 6425);
DISPLAY 1.021277 (-2550 6425);
DISPLAY INVISIBLE (-2550 6425);
FORCEPROP 2 LAST $SEC 1
J 0
(-2550 6425);
DISPLAY 0.680851 (-2550 6425);
PAINT MONO (-2550 6425);
DISPLAY INVISIBLE (-2550 6425);
FORCEPROP 2 LAST CDS_SEC 1
J 0
(-2550 6425);
DISPLAY 1.021277 (-2550 6425);
DISPLAY INVISIBLE (-2550 6425);
FORCEADD Q_RES..2
R 2
(-2725 6200);
FORCEPROP 1 LAST PART_NUMBER CS12402FB01
J 2
(-2765 6025);
DISPLAY 0.510638 (-2765 6025);
DISPLAY INVISIBLE (-2765 6025);
FORCEPROP 1 LAST PACK_TYPE 0402LF
J 2
(-2765 6075);
DISPLAY 0.510638 (-2765 6075);
FORCEPROP 1 LAST MATERIAL CHIP
J 2
(-2765 6125);
DISPLAY 0.510638 (-2765 6125);
FORCEPROP 1 LAST WATTAGE 1/16W
J 2
(-2765 6175);
DISPLAY 0.510638 (-2765 6175);
FORCEPROP 1 LAST TOLERANCE 1%
J 2
(-2770 6225);
DISPLAY 0.510638 (-2770 6225);
FORCEPROP 1 LAST VALUE 240
J 2
(-2770 6275);
DISPLAY 0.510638 (-2770 6275);
FORCEPROP 1 LAST $LOCATION R969
J 2
(-2745 6325);
DISPLAY 0.787234 (-2745 6325);
FORCEPROP 1 LASTPIN (-2725 6300) $PN 1
J 2
(-2730 6262);
DISPLAY 0.787234 (-2730 6262);
FORCEPROP 1 LASTPIN (-2725 6100) $PN 2
J 2
(-2730 6110);
DISPLAY 0.787234 (-2730 6110);
FORCEPROP 1 LAST PATH I43
J 2
(-2775 6375);
DISPLAY 0.978723 (-2775 6375);
PAINT WHITE (-2775 6375);
DISPLAY INVISIBLE (-2775 6375);
FORCEPROP 2 LAST CDS_LIB pure_quanta
J 2
(-2725 6200);
PAINT MONO (-2725 6200);
DISPLAY INVISIBLE (-2725 6200);
FORCEPROP 1 LAST $LOCATION R969
J 0
(-2775 6425);
DISPLAY 1.021277 (-2775 6425);
DISPLAY INVISIBLE (-2775 6425);
FORCEPROP 2 LAST CDS_LOCATION R969
J 0
(-2775 6425);
DISPLAY 1.021277 (-2775 6425);
DISPLAY INVISIBLE (-2775 6425);
FORCEPROP 2 LAST $SEC 1
J 0
(-2775 6425);
DISPLAY 0.680851 (-2775 6425);
PAINT MONO (-2775 6425);
DISPLAY INVISIBLE (-2775 6425);
FORCEPROP 2 LAST CDS_SEC 1
J 0
(-2775 6425);
DISPLAY 1.021277 (-2775 6425);
DISPLAY INVISIBLE (-2775 6425);
FORCEADD Q_RES..1
(-3175 5750);
FORCEPROP 1 LAST PART_NUMBER CS03322FB03
J 0
(-3275 5700);
DISPLAY 0.319149 (-3275 5700);
DISPLAY INVISIBLE (-3275 5700);
FORCEPROP 1 LAST MATERIAL CHIP
J 0
(-2925 5750);
DISPLAY 0.404255 (-2925 5750);
FORCEPROP 1 LAST TOLERANCE 1%
J 0
(-3000 5750);
DISPLAY 0.404255 (-3000 5750);
FORCEPROP 1 LAST VALUE 33.2
J 2
(-3025 5750);
DISPLAY 0.404255 (-3025 5750);
FORCEPROP 1 LAST $LOCATION R993
J 0
(-3400 5750);
DISPLAY 0.638298 (-3400 5750);
FORCEPROP 1 LASTPIN (-3275 5750) $PN 1
J 0
(-3263 5762);
DISPLAY 0.787234 (-3263 5762);
FORCEPROP 1 LASTPIN (-3075 5750) $PN 2
J 0
(-3113 5762);
DISPLAY 0.787234 (-3113 5762);
FORCEPROP 1 LAST PATH I44
J 0
(-3225 5900);
DISPLAY 0.978723 (-3225 5900);
PAINT WHITE (-3225 5900);
DISPLAY INVISIBLE (-3225 5900);
FORCEPROP 1 LAST PACK_TYPE 0402LF
J 0
(-3275 5675);
DISPLAY 0.319149 (-3275 5675);
DISPLAY INVISIBLE (-3275 5675);
FORCEPROP 1 LAST WATTAGE 1/16W
J 2
(-3075 5675);
DISPLAY 0.319149 (-3075 5675);
DISPLAY INVISIBLE (-3075 5675);
FORCEPROP 2 LAST CDS_LIB pure_quanta
J 0
(-3175 5750);
PAINT MONO (-3175 5750);
DISPLAY INVISIBLE (-3175 5750);
FORCEPROP 2 LAST CDS_LOCATION R993
J 0
(-3225 5950);
DISPLAY 1.021277 (-3225 5950);
DISPLAY INVISIBLE (-3225 5950);
FORCEPROP 2 LAST $SEC 1
J 0
(-3225 5950);
DISPLAY 0.680851 (-3225 5950);
PAINT MONO (-3225 5950);
DISPLAY INVISIBLE (-3225 5950);
FORCEPROP 2 LAST CDS_SEC 1
J 0
(-3225 5950);
DISPLAY 1.021277 (-3225 5950);
DISPLAY INVISIBLE (-3225 5950);
FORCEADD OFFPAGE..5
(-4075 5750);
FORCEPROP 2 LAST $XR0 15 
J 0
(-4329 5750);
DISPLAY 0.638298 (-4329 5750);
PAINT MONO (-4329 5750);
FORCEPROP 2 LAST PATH I46
J 0
(-4350 5800);
DISPLAY 1.021277 (-4350 5800);
DISPLAY INVISIBLE (-4350 5800);
FORCEPROP 2 LAST CDS_LIB standard
J 0
(-4075 5750);
PAINT MONO (-4075 5750);
DISPLAY INVISIBLE (-4075 5750);
FORCEPROP 1 LAST OFFPAGE TRUE
J 0
(-3750 5625);
DISPLAY 0.872340 (-3750 5625);
DISPLAY INVISIBLE (-3750 5625);
FORCEPROP 1 LAST COMMENT_BODY TRUE
J 0
(-3975 5675);
DISPLAY 0.872340 (-3975 5675);
PAINT GREEN (-3975 5675);
DISPLAY INVISIBLE (-3975 5675);
FORCEADD OFFPAGE..3
R 2
(-4075 5650);
FORCEPROP 2 LAST $XR0 15 
J 0
(-4354 5650);
DISPLAY 0.638298 (-4354 5650);
PAINT MONO (-4354 5650);
FORCEPROP 2 LAST PATH I47
J 0
(-4400 5700);
DISPLAY 1.021277 (-4400 5700);
DISPLAY INVISIBLE (-4400 5700);
FORCEPROP 2 LAST CDS_LIB standard
J 0
(-4075 5650);
PAINT MONO (-4075 5650);
DISPLAY INVISIBLE (-4075 5650);
FORCEPROP 1 LAST COMMENT_BODY TRUE
J 2
(-4025 5550);
DISPLAY 0.872340 (-4025 5550);
PAINT GREEN (-4025 5550);
DISPLAY INVISIBLE (-4025 5550);
FORCEPROP 1 LAST OFFPAGE TRUE
J 2
(-4400 5525);
DISPLAY 0.872340 (-4400 5525);
DISPLAY INVISIBLE (-4400 5525);
FORCEADD UNIVERSAL_POWER..1
(-2725 4750);
FORCEPROP 3 LASTPIN (-2725 4700) SIG_NAME PVNN_TERM_CPU1\g
J 0
(-2715 4710);
DISPLAY 0.659574 (-2715 4710);
PAINT MONO (-2715 4710);
DISPLAY INVISIBLE (-2715 4710);
FORCEPROP 1 LAST HDL_POWER PVNN_TERM_CPU1
J 1
(-2725 4800);
DISPLAY 0.872340 (-2725 4800);
PAINT GREEN (-2725 4800);
FORCEPROP 2 LAST CDS_LIB logical_power
J 0
(-2725 4750);
PAINT MONO (-2725 4750);
DISPLAY INVISIBLE (-2725 4750);
FORCEPROP 1 LAST PATH I48
J 0
(-2675 4775);
DISPLAY 0.872340 (-2675 4775);
PAINT AQUA (-2675 4775);
DISPLAY INVISIBLE (-2675 4775);
FORCEADD Q_RES..2
R 2
(-2500 4400);
FORCEPROP 1 LAST PART_NUMBER CS12402FB01
J 2
(-2540 4275);
DISPLAY 0.510638 (-2540 4275);
DISPLAY INVISIBLE (-2540 4275);
FORCEPROP 1 LAST MATERIAL CHIP
J 2
(-2540 4325);
DISPLAY 0.510638 (-2540 4325);
FORCEPROP 1 LAST VALUE 240
J 2
(-2545 4475);
DISPLAY 0.510638 (-2545 4475);
FORCEPROP 1 LAST PACK_TYPE 0402LF
J 2
(-2540 4275);
DISPLAY 0.510638 (-2540 4275);
FORCEPROP 1 LAST TOLERANCE 1%
J 2
(-2545 4425);
DISPLAY 0.510638 (-2545 4425);
FORCEPROP 1 LAST WATTAGE 1/16W
J 2
(-2540 4375);
DISPLAY 0.510638 (-2540 4375);
FORCEPROP 1 LAST $LOCATION R972
J 2
(-2520 4525);
DISPLAY 0.787234 (-2520 4525);
FORCEPROP 1 LASTPIN (-2500 4500) $PN 1
J 2
(-2505 4462);
DISPLAY 0.787234 (-2505 4462);
FORCEPROP 1 LASTPIN (-2500 4300) $PN 2
J 2
(-2505 4310);
DISPLAY 0.787234 (-2505 4310);
FORCEPROP 2 LAST CDS_LIB pure_quanta
J 0
(-2500 4400);
PAINT MONO (-2500 4400);
DISPLAY INVISIBLE (-2500 4400);
FORCEPROP 1 LAST PATH I49
J 2
(-2550 4575);
DISPLAY 0.978723 (-2550 4575);
PAINT WHITE (-2550 4575);
DISPLAY INVISIBLE (-2550 4575);
FORCEPROP 1 LAST $LOCATION R972
J 0
(-2550 4625);
DISPLAY 1.021277 (-2550 4625);
DISPLAY INVISIBLE (-2550 4625);
FORCEPROP 2 LAST CDS_LOCATION R972
J 0
(-2550 4625);
DISPLAY 1.021277 (-2550 4625);
DISPLAY INVISIBLE (-2550 4625);
FORCEPROP 2 LAST $SEC 1
J 0
(-2550 4625);
DISPLAY 0.680851 (-2550 4625);
PAINT MONO (-2550 4625);
DISPLAY INVISIBLE (-2550 4625);
FORCEPROP 2 LAST CDS_SEC 1
J 0
(-2550 4625);
DISPLAY 1.021277 (-2550 4625);
DISPLAY INVISIBLE (-2550 4625);
FORCEADD OFFPAGE..3
(2175 3850);
FORCEPROP 2 LAST $XR0 236 
J 0
(2389 3850);
DISPLAY 0.638298 (2389 3850);
PAINT MONO (2389 3850);
FORCEPROP 2 LAST CDS_LIB standard
J 0
(2175 3850);
PAINT MONO (2175 3850);
DISPLAY INVISIBLE (2175 3850);
FORCEPROP 1 LAST COMMENT_BODY TRUE
J 0
(2125 3750);
DISPLAY 0.872340 (2125 3750);
PAINT GREEN (2125 3750);
DISPLAY INVISIBLE (2125 3750);
FORCEPROP 1 LAST OFFPAGE TRUE
J 0
(2500 3725);
DISPLAY 0.872340 (2500 3725);
PAINT GREEN (2500 3725);
DISPLAY INVISIBLE (2500 3725);
FORCEPROP 2 LAST PATH I5
J 0
(2400 3900);
DISPLAY 1.021277 (2400 3900);
DISPLAY INVISIBLE (2400 3900);
FORCEADD Q_RES..2
R 2
(-2725 4400);
FORCEPROP 1 LAST PART_NUMBER CS12402FB01
J 2
(-2765 4225);
DISPLAY 0.510638 (-2765 4225);
DISPLAY INVISIBLE (-2765 4225);
FORCEPROP 1 LAST WATTAGE 1/16W
J 2
(-2765 4375);
DISPLAY 0.510638 (-2765 4375);
FORCEPROP 1 LAST TOLERANCE 1%
J 2
(-2770 4425);
DISPLAY 0.510638 (-2770 4425);
FORCEPROP 1 LAST PACK_TYPE 0402LF
J 2
(-2765 4275);
DISPLAY 0.510638 (-2765 4275);
FORCEPROP 1 LAST MATERIAL CHIP
J 2
(-2765 4325);
DISPLAY 0.510638 (-2765 4325);
FORCEPROP 1 LAST VALUE 240
J 2
(-2770 4475);
DISPLAY 0.510638 (-2770 4475);
FORCEPROP 1 LAST $LOCATION R970
J 2
(-2745 4525);
DISPLAY 0.787234 (-2745 4525);
FORCEPROP 1 LASTPIN (-2725 4500) $PN 1
J 2
(-2730 4462);
DISPLAY 0.787234 (-2730 4462);
FORCEPROP 1 LASTPIN (-2725 4300) $PN 2
J 2
(-2730 4310);
DISPLAY 0.787234 (-2730 4310);
FORCEPROP 2 LAST CDS_LIB pure_quanta
J 2
(-2725 4400);
PAINT MONO (-2725 4400);
DISPLAY INVISIBLE (-2725 4400);
FORCEPROP 1 LAST PATH I50
J 2
(-2775 4575);
DISPLAY 0.978723 (-2775 4575);
PAINT WHITE (-2775 4575);
DISPLAY INVISIBLE (-2775 4575);
FORCEPROP 1 LAST $LOCATION R970
J 0
(-2775 4625);
DISPLAY 1.021277 (-2775 4625);
DISPLAY INVISIBLE (-2775 4625);
FORCEPROP 2 LAST CDS_LOCATION R970
J 0
(-2775 4625);
DISPLAY 1.021277 (-2775 4625);
DISPLAY INVISIBLE (-2775 4625);
FORCEPROP 2 LAST $SEC 1
J 0
(-2775 4625);
DISPLAY 0.680851 (-2775 4625);
PAINT MONO (-2775 4625);
DISPLAY INVISIBLE (-2775 4625);
FORCEPROP 2 LAST CDS_SEC 1
J 0
(-2775 4625);
DISPLAY 1.021277 (-2775 4625);
DISPLAY INVISIBLE (-2775 4625);
FORCEADD Q_RES..1
(-3175 3950);
FORCEPROP 1 LAST PART_NUMBER CS03322FB03
J 0
(-3275 3900);
DISPLAY 0.319149 (-3275 3900);
DISPLAY INVISIBLE (-3275 3900);
FORCEPROP 1 LAST VALUE 33.2
J 2
(-3000 3950);
DISPLAY 0.404255 (-3000 3950);
FORCEPROP 1 LAST MATERIAL CHIP
J 0
(-2900 3950);
DISPLAY 0.404255 (-2900 3950);
FORCEPROP 1 LAST TOLERANCE 1%
J 0
(-2975 3950);
DISPLAY 0.404255 (-2975 3950);
FORCEPROP 1 LAST $LOCATION R995
J 0
(-3400 3950);
DISPLAY 0.638298 (-3400 3950);
FORCEPROP 1 LASTPIN (-3275 3950) $PN 1
J 0
(-3263 3962);
DISPLAY 0.787234 (-3263 3962);
FORCEPROP 1 LASTPIN (-3075 3950) $PN 2
J 0
(-3113 3962);
DISPLAY 0.787234 (-3113 3962);
FORCEPROP 1 LAST PACK_TYPE 0402LF
J 0
(-3275 3875);
DISPLAY 0.319149 (-3275 3875);
DISPLAY INVISIBLE (-3275 3875);
FORCEPROP 1 LAST WATTAGE 1/16W
J 2
(-3075 3875);
DISPLAY 0.319149 (-3075 3875);
DISPLAY INVISIBLE (-3075 3875);
FORCEPROP 2 LAST CDS_LIB pure_quanta
J 0
(-3175 3950);
PAINT MONO (-3175 3950);
DISPLAY INVISIBLE (-3175 3950);
FORCEPROP 1 LAST PATH I51
J 0
(-3225 4100);
DISPLAY 0.978723 (-3225 4100);
PAINT WHITE (-3225 4100);
DISPLAY INVISIBLE (-3225 4100);
FORCEPROP 2 LAST CDS_LOCATION R995
J 0
(-3225 4150);
DISPLAY 1.021277 (-3225 4150);
DISPLAY INVISIBLE (-3225 4150);
FORCEPROP 2 LAST $SEC 1
J 0
(-3225 4150);
DISPLAY 0.680851 (-3225 4150);
PAINT MONO (-3225 4150);
DISPLAY INVISIBLE (-3225 4150);
FORCEPROP 2 LAST CDS_SEC 1
J 0
(-3225 4150);
DISPLAY 1.021277 (-3225 4150);
DISPLAY INVISIBLE (-3225 4150);
FORCEADD OFFPAGE..5
(-4075 3950);
FORCEPROP 2 LAST $XR0 46 
J 0
(-4329 3950);
DISPLAY 0.638298 (-4329 3950);
PAINT MONO (-4329 3950);
FORCEPROP 2 LAST PATH I53
J 0
(-4350 4000);
DISPLAY 1.021277 (-4350 4000);
DISPLAY INVISIBLE (-4350 4000);
FORCEPROP 2 LAST CDS_LIB standard
J 0
(-4075 3950);
PAINT MONO (-4075 3950);
DISPLAY INVISIBLE (-4075 3950);
FORCEPROP 1 LAST OFFPAGE TRUE
J 0
(-3750 3825);
DISPLAY 0.872340 (-3750 3825);
DISPLAY INVISIBLE (-3750 3825);
FORCEPROP 1 LAST COMMENT_BODY TRUE
J 0
(-3975 3875);
DISPLAY 0.872340 (-3975 3875);
PAINT GREEN (-3975 3875);
DISPLAY INVISIBLE (-3975 3875);
FORCEADD OFFPAGE..3
R 2
(-4075 3850);
FORCEPROP 2 LAST $XR0 46 
J 0
(-4354 3850);
DISPLAY 0.638298 (-4354 3850);
PAINT MONO (-4354 3850);
FORCEPROP 2 LAST CDS_LIB standard
J 0
(-4075 3850);
PAINT MONO (-4075 3850);
DISPLAY INVISIBLE (-4075 3850);
FORCEPROP 1 LAST COMMENT_BODY TRUE
J 2
(-4025 3750);
DISPLAY 0.872340 (-4025 3750);
PAINT GREEN (-4025 3750);
DISPLAY INVISIBLE (-4025 3750);
FORCEPROP 1 LAST OFFPAGE TRUE
J 2
(-4400 3725);
DISPLAY 0.872340 (-4400 3725);
DISPLAY INVISIBLE (-4400 3725);
FORCEPROP 2 LAST PATH I54
J 0
(-4400 3900);
DISPLAY 1.021277 (-4400 3900);
DISPLAY INVISIBLE (-4400 3900);
FORCEADD Q_RES..2
(1350 6200);
FORCEPROP 1 LAST PART_NUMBER CS15602FB03
J 0
(1390 6025);
DISPLAY 0.510638 (1390 6025);
DISPLAY INVISIBLE (1390 6025);
FORCEPROP 1 LAST PACK_TYPE 0402LF
J 0
(1390 6075);
DISPLAY 0.510638 (1390 6075);
FORCEPROP 1 LAST MATERIAL CHIP
J 0
(1390 6125);
DISPLAY 0.510638 (1390 6125);
FORCEPROP 1 LAST TOLERANCE 1%
J 0
(1395 6225);
DISPLAY 0.510638 (1395 6225);
FORCEPROP 1 LAST VALUE 560
J 0
(1395 6275);
DISPLAY 0.510638 (1395 6275);
FORCEPROP 1 LAST WATTAGE 1/16W
J 0
(1390 6175);
DISPLAY 0.510638 (1390 6175);
FORCEPROP 1 LAST $LOCATION R979
J 0
(1395 6325);
DISPLAY 0.787234 (1395 6325);
FORCEPROP 1 LASTPIN (1350 6300) $PN 1
J 0
(1355 6262);
DISPLAY 0.787234 (1355 6262);
FORCEPROP 1 LASTPIN (1350 6100) $PN 2
J 0
(1355 6110);
DISPLAY 0.787234 (1355 6110);
FORCEPROP 2 LAST CDS_LIB pure_quanta
J 0
(1350 6200);
PAINT MONO (1350 6200);
DISPLAY INVISIBLE (1350 6200);
FORCEPROP 1 LAST PATH I6
J 0
(1400 6375);
DISPLAY 0.978723 (1400 6375);
PAINT WHITE (1400 6375);
DISPLAY INVISIBLE (1400 6375);
FORCEPROP 2 LAST CDS_LOCATION R979
J 0
(1400 6425);
DISPLAY 1.021277 (1400 6425);
DISPLAY INVISIBLE (1400 6425);
FORCEPROP 2 LAST $SEC 1
J 0
(1400 6425);
DISPLAY 0.680851 (1400 6425);
PAINT MONO (1400 6425);
DISPLAY INVISIBLE (1400 6425);
FORCEPROP 2 LAST CDS_SEC 1
J 0
(1400 6425);
DISPLAY 1.021277 (1400 6425);
DISPLAY INVISIBLE (1400 6425);
FORCEADD Q_RES..1
(1475 8850);
FORCEPROP 1 LAST PART_NUMBER CS00002JB13
J 0
(1425 8900);
DISPLAY 0.404255 (1425 8900);
DISPLAY INVISIBLE (1425 8900);
FORCEPROP 1 LAST VALUE 0
J 2
(1625 8850);
DISPLAY 0.510638 (1625 8850);
FORCEPROP 1 LAST TOLERANCE 5%
J 0
(1650 8850);
DISPLAY 0.510638 (1650 8850);
FORCEPROP 1 LAST MATERIAL CHIP
J 0
(1725 8850);
DISPLAY 0.510638 (1725 8850);
FORCEPROP 1 LAST $LOCATION R2208
J 0
(1300 8850);
DISPLAY 0.510638 (1300 8850);
FORCEPROP 1 LASTPIN (1375 8850) $PN 1
J 0
(1387 8862);
DISPLAY 0.787234 (1387 8862);
PAINT MONO (1387 8862);
FORCEPROP 1 LASTPIN (1575 8850) $PN 2
J 0
(1537 8862);
DISPLAY 0.787234 (1537 8862);
PAINT MONO (1537 8862);
FORCEPROP 1 LAST PACK_TYPE 0402LF
J 0
(1725 8850);
DISPLAY 0.510638 (1725 8850);
DISPLAY INVISIBLE (1725 8850);
FORCEPROP 1 LAST WATTAGE 1/16W
J 2
(1650 8925);
DISPLAY 0.404255 (1650 8925);
DISPLAY INVISIBLE (1650 8925);
FORCEPROP 2 LAST CDS_LIB pure_quanta
J 0
(1475 8850);
DISPLAY INVISIBLE (1475 8850);
FORCEPROP 1 LAST PATH I62
J 0
(1425 9000);
DISPLAY 0.978723 (1425 9000);
PAINT WHITE (1425 9000);
DISPLAY INVISIBLE (1425 9000);
FORCEPROP 0 LAST CDS_LOCATION R2208
J 0
(1225 8900);
DISPLAY 1.021277 (1225 8900);
DISPLAY INVISIBLE (1225 8900);
FORCEPROP 0 LAST $SEC 1
J 0
(1225 8900);
DISPLAY 0.680851 (1225 8900);
PAINT MONO (1225 8900);
DISPLAY INVISIBLE (1225 8900);
FORCEPROP 0 LAST CDS_SEC 1
J 0
(1225 8900);
DISPLAY 1.021277 (1225 8900);
DISPLAY INVISIBLE (1225 8900);
FORCEADD Q_RES..1
(1475 8900);
FORCEPROP 1 LAST PART_NUMBER CS00002JB13
J 0
(1425 8950);
DISPLAY 0.404255 (1425 8950);
DISPLAY INVISIBLE (1425 8950);
FORCEPROP 1 LAST VALUE 0
J 2
(1625 8900);
DISPLAY 0.510638 (1625 8900);
FORCEPROP 1 LAST TOLERANCE 5%
J 0
(1650 8900);
DISPLAY 0.510638 (1650 8900);
FORCEPROP 1 LAST MATERIAL CHIP
J 0
(1725 8900);
DISPLAY 0.510638 (1725 8900);
FORCEPROP 1 LAST $LOCATION R2209
J 0
(1300 8900);
DISPLAY 0.510638 (1300 8900);
FORCEPROP 1 LASTPIN (1375 8900) $PN 1
J 0
(1390 8910);
DISPLAY 0.787234 (1390 8910);
PAINT MONO (1390 8910);
FORCEPROP 1 LASTPIN (1575 8900) $PN 2
J 0
(1540 8910);
DISPLAY 0.787234 (1540 8910);
PAINT MONO (1540 8910);
FORCEPROP 1 LAST PATH I63
J 0
(1425 9050);
DISPLAY 0.978723 (1425 9050);
PAINT WHITE (1425 9050);
DISPLAY INVISIBLE (1425 9050);
FORCEPROP 2 LAST CDS_LIB pure_quanta
J 0
(1475 8900);
DISPLAY INVISIBLE (1475 8900);
FORCEPROP 1 LAST WATTAGE 1/16W
J 2
(1650 8975);
DISPLAY 0.404255 (1650 8975);
DISPLAY INVISIBLE (1650 8975);
FORCEPROP 1 LAST PACK_TYPE 0402LF
J 0
(1725 8900);
DISPLAY 0.510638 (1725 8900);
DISPLAY INVISIBLE (1725 8900);
FORCEPROP 0 LAST CDS_LOCATION R2209
J 0
(1225 8950);
DISPLAY 1.021277 (1225 8950);
DISPLAY INVISIBLE (1225 8950);
FORCEPROP 0 LAST $SEC 1
J 0
(1225 8950);
DISPLAY 0.680851 (1225 8950);
PAINT MONO (1225 8950);
DISPLAY INVISIBLE (1225 8950);
FORCEPROP 0 LAST CDS_SEC 1
J 0
(1225 8950);
DISPLAY 1.021277 (1225 8950);
DISPLAY INVISIBLE (1225 8950);
FORCEADD Q_RES..1
(1475 8550);
FORCEPROP 1 LAST PART_NUMBER CS00002JB13
J 0
(1425 8600);
DISPLAY 0.404255 (1425 8600);
DISPLAY INVISIBLE (1425 8600);
FORCEPROP 1 LAST TOLERANCE 5%
J 0
(1650 8550);
DISPLAY 0.510638 (1650 8550);
FORCEPROP 1 LAST VALUE 0
J 2
(1625 8550);
DISPLAY 0.510638 (1625 8550);
FORCEPROP 1 LAST MATERIAL CHIP
J 0
(1725 8550);
DISPLAY 0.510638 (1725 8550);
FORCEPROP 1 LAST $LOCATION R2210
J 0
(1300 8550);
DISPLAY 0.510638 (1300 8550);
FORCEPROP 1 LASTPIN (1375 8550) $PN 1
J 0
(1387 8562);
DISPLAY 0.787234 (1387 8562);
PAINT MONO (1387 8562);
FORCEPROP 1 LASTPIN (1575 8550) $PN 2
J 0
(1537 8562);
DISPLAY 0.787234 (1537 8562);
PAINT MONO (1537 8562);
FORCEPROP 2 LAST CDS_LIB pure_quanta
J 0
(1475 8550);
DISPLAY INVISIBLE (1475 8550);
FORCEPROP 1 LAST WATTAGE 1/16W
J 2
(1650 8625);
DISPLAY 0.404255 (1650 8625);
DISPLAY INVISIBLE (1650 8625);
FORCEPROP 1 LAST PACK_TYPE 0402LF
J 0
(1725 8550);
DISPLAY 0.510638 (1725 8550);
DISPLAY INVISIBLE (1725 8550);
FORCEPROP 1 LAST PATH I64
J 0
(1425 8700);
DISPLAY 0.978723 (1425 8700);
PAINT WHITE (1425 8700);
DISPLAY INVISIBLE (1425 8700);
FORCEPROP 0 LAST CDS_LOCATION R2210
J 0
(1225 8600);
DISPLAY 1.021277 (1225 8600);
DISPLAY INVISIBLE (1225 8600);
FORCEPROP 0 LAST $SEC 1
J 0
(1225 8600);
DISPLAY 0.680851 (1225 8600);
PAINT MONO (1225 8600);
DISPLAY INVISIBLE (1225 8600);
FORCEPROP 0 LAST CDS_SEC 1
J 0
(1225 8600);
DISPLAY 1.021277 (1225 8600);
DISPLAY INVISIBLE (1225 8600);
FORCEADD Q_RES..1
(1475 8600);
FORCEPROP 1 LAST PART_NUMBER CS00002JB13
J 0
(1425 8650);
DISPLAY 0.404255 (1425 8650);
DISPLAY INVISIBLE (1425 8650);
FORCEPROP 1 LAST TOLERANCE 5%
J 0
(1650 8600);
DISPLAY 0.510638 (1650 8600);
FORCEPROP 1 LAST VALUE 0
J 2
(1625 8600);
DISPLAY 0.510638 (1625 8600);
FORCEPROP 1 LAST MATERIAL CHIP
J 0
(1725 8600);
DISPLAY 0.510638 (1725 8600);
FORCEPROP 1 LAST $LOCATION R2211
J 0
(1300 8600);
DISPLAY 0.510638 (1300 8600);
FORCEPROP 1 LASTPIN (1375 8600) $PN 1
J 0
(1387 8612);
DISPLAY 0.787234 (1387 8612);
PAINT MONO (1387 8612);
FORCEPROP 1 LASTPIN (1575 8600) $PN 2
J 0
(1537 8612);
DISPLAY 0.787234 (1537 8612);
PAINT MONO (1537 8612);
FORCEPROP 1 LAST PACK_TYPE 0402LF
J 0
(1725 8600);
DISPLAY 0.510638 (1725 8600);
DISPLAY INVISIBLE (1725 8600);
FORCEPROP 1 LAST WATTAGE 1/16W
J 2
(1650 8675);
DISPLAY 0.404255 (1650 8675);
DISPLAY INVISIBLE (1650 8675);
FORCEPROP 2 LAST CDS_LIB pure_quanta
J 0
(1475 8600);
DISPLAY INVISIBLE (1475 8600);
FORCEPROP 1 LAST PATH I65
J 0
(1425 8750);
DISPLAY 0.978723 (1425 8750);
PAINT WHITE (1425 8750);
DISPLAY INVISIBLE (1425 8750);
FORCEPROP 0 LAST CDS_LOCATION R2211
J 0
(1225 8650);
DISPLAY 1.021277 (1225 8650);
DISPLAY INVISIBLE (1225 8650);
FORCEPROP 0 LAST $SEC 1
J 0
(1225 8650);
DISPLAY 0.680851 (1225 8650);
PAINT MONO (1225 8650);
DISPLAY INVISIBLE (1225 8650);
FORCEPROP 0 LAST CDS_SEC 1
J 0
(1225 8650);
DISPLAY 1.021277 (1225 8650);
DISPLAY INVISIBLE (1225 8650);
FORCEADD UNIVERSAL_GND..1
(-975 9050);
FORCEPROP 3 LASTPIN (-975 9100) SIG_NAME GND\g
J 0
(-965 9110);
DISPLAY 0.659574 (-965 9110);
PAINT MONO (-965 9110);
DISPLAY INVISIBLE (-965 9110);
FORCEPROP 1 LAST HDL_POWER GND
J 1
(-950 8975);
DISPLAY 0.872340 (-950 8975);
PAINT GREEN (-950 8975);
DISPLAY INVISIBLE (-950 8975);
FORCEPROP 1 LAST PATH I67
J 0
(-900 9050);
DISPLAY 0.872340 (-900 9050);
PAINT AQUA (-900 9050);
DISPLAY INVISIBLE (-900 9050);
FORCEPROP 2 LAST CDS_LIB logical_power
J 0
(-975 9050);
DISPLAY INVISIBLE (-975 9050);
FORCEADD Q_CAP..1
R 2
(-975 9275);
FORCEPROP 1 LAST PART_NUMBER CH4104K1B00
J 2
(-1025 9125);
DISPLAY 0.510638 (-1025 9125);
DISPLAY INVISIBLE (-1025 9125);
FORCEPROP 1 LAST VOLTAGE 25V
J 2
(-1025 9275);
DISPLAY 0.510638 (-1025 9275);
FORCEPROP 1 LAST TOLERANCE 10%
J 2
(-1025 9225);
DISPLAY 0.510638 (-1025 9225);
FORCEPROP 1 LAST MATERIAL X7R
J 2
(-1025 9175);
DISPLAY 0.510638 (-1025 9175);
FORCEPROP 1 LAST VALUE 0.1UF
J 2
(-1025 9325);
DISPLAY 0.510638 (-1025 9325);
FORCEPROP 1 LAST PACK_TYPE 0402
J 2
(-1025 9075);
DISPLAY 0.510638 (-1025 9075);
FORCEPROP 1 LAST $LOCATION C1613
J 2
(-1025 9375);
DISPLAY 0.978723 (-1025 9375);
FORCEPROP 1 LASTPIN (-975 9375) $PN 1
J 2
(-985 9355);
DISPLAY 0.787234 (-985 9355);
PAINT MONO (-985 9355);
FORCEPROP 1 LASTPIN (-975 9175) $PN 2
J 2
(-985 9155);
DISPLAY 0.787234 (-985 9155);
PAINT MONO (-985 9155);
FORCEPROP 1 LAST PATH I68
J 2
(-1025 9425);
DISPLAY 0.978723 (-1025 9425);
PAINT WHITE (-1025 9425);
DISPLAY INVISIBLE (-1025 9425);
FORCEPROP 2 LAST CDS_LIB pure_quanta
J 0
(-975 9275);
DISPLAY INVISIBLE (-975 9275);
FORCEPROP 0 LAST CDS_LOCATION C1613
J 0
(-1025 9425);
DISPLAY 1.021277 (-1025 9425);
DISPLAY INVISIBLE (-1025 9425);
FORCEPROP 0 LAST $SEC 1
J 0
(-1025 9425);
DISPLAY 0.680851 (-1025 9425);
PAINT MONO (-1025 9425);
DISPLAY INVISIBLE (-1025 9425);
FORCEPROP 0 LAST CDS_SEC 1
J 0
(-1025 9425);
DISPLAY 1.021277 (-1025 9425);
DISPLAY INVISIBLE (-1025 9425);
FORCEADD UNIVERSAL_GND..1
(-825 7675);
FORCEPROP 3 LASTPIN (-825 7725) SIG_NAME GND\g
J 0
(-815 7735);
DISPLAY 0.659574 (-815 7735);
PAINT MONO (-815 7735);
DISPLAY INVISIBLE (-815 7735);
FORCEPROP 2 LAST CDS_LIB logical_power
J 0
(-825 7675);
DISPLAY INVISIBLE (-825 7675);
FORCEPROP 1 LAST PATH I69
J 0
(-750 7675);
DISPLAY 0.872340 (-750 7675);
PAINT AQUA (-750 7675);
DISPLAY INVISIBLE (-750 7675);
FORCEPROP 1 LAST HDL_POWER GND
J 1
(-800 7600);
DISPLAY 0.872340 (-800 7600);
PAINT GREEN (-800 7600);
DISPLAY INVISIBLE (-800 7600);
FORCEADD UNIVERSAL_POWER..1
(1150 6550);
FORCEPROP 3 LASTPIN (1150 6500) SIG_NAME P3V3_AUX\g
J 0
(1160 6510);
DISPLAY 0.659574 (1160 6510);
PAINT MONO (1160 6510);
DISPLAY INVISIBLE (1160 6510);
FORCEPROP 1 LAST HDL_POWER P3V3_AUX
J 1
(1150 6600);
DISPLAY 0.872340 (1150 6600);
PAINT GREEN (1150 6600);
FORCEPROP 1 LAST PATH I7
J 0
(1200 6575);
DISPLAY 0.872340 (1200 6575);
PAINT AQUA (1200 6575);
DISPLAY INVISIBLE (1200 6575);
FORCEPROP 2 LAST CDS_LIB logical_power
J 0
(1150 6550);
PAINT MONO (1150 6550);
DISPLAY INVISIBLE (1150 6550);
FORCEADD UNIVERSAL_POWER..1
(-975 9600);
FORCEPROP 3 LASTPIN (-975 9550) SIG_NAME P3V3_AUX\g
J 0
(-965 9560);
DISPLAY 0.659574 (-965 9560);
PAINT MONO (-965 9560);
DISPLAY INVISIBLE (-965 9560);
FORCEPROP 1 LAST HDL_POWER P3V3_AUX
J 1
(-975 9650);
DISPLAY 0.872340 (-975 9650);
PAINT GREEN (-975 9650);
FORCEPROP 2 LAST CDS_LIB logical_power
J 0
(-975 9600);
DISPLAY INVISIBLE (-975 9600);
FORCEPROP 1 LAST PATH I70
J 0
(-925 9625);
DISPLAY 0.872340 (-925 9625);
PAINT AQUA (-925 9625);
DISPLAY INVISIBLE (-925 9625);
FORCEADD Q_RES..2
(1150 6200);
FORCEPROP 1 LAST PART_NUMBER CS15602FB03
J 0
(1190 6025);
DISPLAY 0.638298 (1190 6025);
DISPLAY INVISIBLE (1190 6025);
FORCEPROP 1 LAST VALUE 560
J 0
(1195 6275);
DISPLAY 0.510638 (1195 6275);
FORCEPROP 1 LAST WATTAGE 1/16W
J 0
(1190 6175);
DISPLAY 0.510638 (1190 6175);
FORCEPROP 1 LAST MATERIAL CHIP
J 0
(1190 6125);
DISPLAY 0.510638 (1190 6125);
FORCEPROP 1 LAST PACK_TYPE 0402LF
J 0
(1190 6075);
DISPLAY 0.510638 (1190 6075);
FORCEPROP 1 LAST TOLERANCE 1%
J 0
(1195 6225);
DISPLAY 0.510638 (1195 6225);
FORCEPROP 1 LAST $LOCATION R977
J 0
(1195 6325);
DISPLAY 0.787234 (1195 6325);
FORCEPROP 1 LASTPIN (1150 6300) $PN 1
J 0
(1155 6262);
DISPLAY 0.787234 (1155 6262);
FORCEPROP 1 LASTPIN (1150 6100) $PN 2
J 0
(1155 6110);
DISPLAY 0.787234 (1155 6110);
FORCEPROP 2 LAST CDS_LIB pure_quanta
J 0
(1150 6200);
PAINT MONO (1150 6200);
DISPLAY INVISIBLE (1150 6200);
FORCEPROP 1 LAST PATH I8
J 0
(1200 6375);
DISPLAY 0.978723 (1200 6375);
PAINT WHITE (1200 6375);
DISPLAY INVISIBLE (1200 6375);
FORCEPROP 2 LAST CDS_LOCATION R977
J 0
(1200 6425);
DISPLAY 1.021277 (1200 6425);
DISPLAY INVISIBLE (1200 6425);
FORCEPROP 2 LAST $SEC 1
J 0
(1200 6425);
DISPLAY 0.680851 (1200 6425);
PAINT MONO (1200 6425);
DISPLAY INVISIBLE (1200 6425);
FORCEPROP 2 LAST CDS_SEC 1
J 0
(1200 6425);
DISPLAY 1.021277 (1200 6425);
DISPLAY INVISIBLE (1200 6425);
FORCEADD Q_RES..2
(-4100 8100);
FORCEPROP 1 LAST PART_NUMBER CS31002FB08
J 0
(-4060 7975);
DISPLAY 0.510638 (-4060 7975);
DISPLAY INVISIBLE (-4060 7975);
FORCEPROP 1 LAST MATERIAL EMPTY
J 0
(-4060 8025);
DISPLAY 0.638298 (-4060 8025);
PAINT RED (-4060 8025);
FORCEPROP 1 LAST VALUE 10K
J 0
(-4055 8175);
DISPLAY 0.638298 (-4055 8175);
FORCEPROP 1 LAST WATTAGE 1/16W
J 0
(-4060 8075);
DISPLAY 0.638298 (-4060 8075);
FORCEPROP 1 LAST TOLERANCE 1%
J 0
(-4055 8125);
DISPLAY 0.638298 (-4055 8125);
FORCEPROP 1 LAST PACK_TYPE 0402LF
J 0
(-4060 7925);
DISPLAY 0.638298 (-4060 7925);
FORCEPROP 1 LAST $LOCATION R2310
J 0
(-4055 8225);
DISPLAY 0.978723 (-4055 8225);
FORCEPROP 1 LASTPIN (-4100 8200) $PN 1
J 0
(-4095 8162);
DISPLAY 0.787234 (-4095 8162);
PAINT MONO (-4095 8162);
FORCEPROP 1 LASTPIN (-4100 8000) $PN 2
J 0
(-4095 8010);
DISPLAY 0.787234 (-4095 8010);
PAINT MONO (-4095 8010);
FORCEPROP 2 LAST CDS_LIB pure_quanta
J 0
(-4100 8100);
DISPLAY INVISIBLE (-4100 8100);
FORCEPROP 1 LAST PATH I83
J 0
(-4050 8275);
DISPLAY 0.978723 (-4050 8275);
PAINT WHITE (-4050 8275);
DISPLAY INVISIBLE (-4050 8275);
FORCEPROP 0 LAST CDS_LOCATION R2310
J 0
(-4050 8275);
DISPLAY 1.021277 (-4050 8275);
DISPLAY INVISIBLE (-4050 8275);
FORCEPROP 0 LAST $SEC 1
J 0
(-4050 8275);
DISPLAY 0.680851 (-4050 8275);
PAINT MONO (-4050 8275);
DISPLAY INVISIBLE (-4050 8275);
FORCEPROP 0 LAST CDS_SEC 1
J 0
(-4050 8275);
DISPLAY 1.021277 (-4050 8275);
DISPLAY INVISIBLE (-4050 8275);
FORCEADD Q_RES..2
(-4350 8100);
FORCEPROP 1 LAST PART_NUMBER CS31002FB08
J 0
(-4310 7975);
DISPLAY 0.510638 (-4310 7975);
DISPLAY INVISIBLE (-4310 7975);
FORCEPROP 1 LAST PACK_TYPE 0402LF
J 0
(-4310 7975);
DISPLAY 0.638298 (-4310 7975);
FORCEPROP 1 LAST MATERIAL EMPTY
J 0
(-4310 8025);
DISPLAY 0.638298 (-4310 8025);
PAINT RED (-4310 8025);
FORCEPROP 1 LAST WATTAGE 1/16W
J 0
(-4310 8075);
DISPLAY 0.638298 (-4310 8075);
FORCEPROP 1 LAST TOLERANCE 1%
J 0
(-4305 8125);
DISPLAY 0.638298 (-4305 8125);
FORCEPROP 1 LAST VALUE 10K
J 0
(-4305 8175);
DISPLAY 0.638298 (-4305 8175);
FORCEPROP 1 LAST $LOCATION R2308
J 0
(-4305 8225);
DISPLAY 0.978723 (-4305 8225);
FORCEPROP 1 LASTPIN (-4350 8200) $PN 1
J 0
(-4345 8162);
DISPLAY 0.787234 (-4345 8162);
PAINT MONO (-4345 8162);
FORCEPROP 1 LASTPIN (-4350 8000) $PN 2
J 0
(-4345 8010);
DISPLAY 0.787234 (-4345 8010);
PAINT MONO (-4345 8010);
FORCEPROP 1 LAST PATH I84
J 0
(-4300 8275);
DISPLAY 0.978723 (-4300 8275);
PAINT WHITE (-4300 8275);
DISPLAY INVISIBLE (-4300 8275);
FORCEPROP 2 LAST CDS_LIB pure_quanta
J 0
(-4350 8100);
DISPLAY INVISIBLE (-4350 8100);
FORCEPROP 0 LAST CDS_LOCATION R2308
J 0
(-4300 8275);
DISPLAY 1.021277 (-4300 8275);
DISPLAY INVISIBLE (-4300 8275);
FORCEPROP 0 LAST $SEC 1
J 0
(-4300 8275);
DISPLAY 0.680851 (-4300 8275);
PAINT MONO (-4300 8275);
DISPLAY INVISIBLE (-4300 8275);
FORCEPROP 0 LAST CDS_SEC 1
J 0
(-4300 8275);
DISPLAY 1.021277 (-4300 8275);
DISPLAY INVISIBLE (-4300 8275);
FORCEADD Q_RES..2
(-4350 7450);
FORCEPROP 1 LAST PART_NUMBER CS21002FB06
J 0
(-4310 7325);
DISPLAY 0.510638 (-4310 7325);
DISPLAY INVISIBLE (-4310 7325);
FORCEPROP 1 LAST WATTAGE 1/16W
J 0
(-4310 7425);
DISPLAY 0.638298 (-4310 7425);
FORCEPROP 1 LAST VALUE 1K
J 0
(-4305 7525);
DISPLAY 0.638298 (-4305 7525);
FORCEPROP 1 LAST MATERIAL CHIP
J 0
(-4310 7375);
DISPLAY 0.638298 (-4310 7375);
FORCEPROP 1 LAST TOLERANCE 1%
J 0
(-4305 7475);
DISPLAY 0.638298 (-4305 7475);
FORCEPROP 1 LAST PACK_TYPE 0402LF
J 0
(-4310 7325);
DISPLAY 0.638298 (-4310 7325);
FORCEPROP 1 LAST $LOCATION R2309
J 0
(-4305 7575);
DISPLAY 0.978723 (-4305 7575);
FORCEPROP 1 LASTPIN (-4350 7550) $PN 1
J 0
(-4345 7512);
DISPLAY 0.787234 (-4345 7512);
PAINT MONO (-4345 7512);
FORCEPROP 1 LASTPIN (-4350 7350) $PN 2
J 0
(-4345 7360);
DISPLAY 0.787234 (-4345 7360);
PAINT MONO (-4345 7360);
FORCEPROP 1 LAST PATH I85
J 0
(-4300 7625);
DISPLAY 0.978723 (-4300 7625);
PAINT WHITE (-4300 7625);
DISPLAY INVISIBLE (-4300 7625);
FORCEPROP 2 LAST CDS_LIB pure_quanta
J 0
(-4350 7450);
DISPLAY INVISIBLE (-4350 7450);
FORCEPROP 0 LAST CDS_LOCATION R2309
J 0
(-4300 7625);
DISPLAY 1.021277 (-4300 7625);
DISPLAY INVISIBLE (-4300 7625);
FORCEPROP 0 LAST $SEC 1
J 0
(-4300 7625);
DISPLAY 0.680851 (-4300 7625);
PAINT MONO (-4300 7625);
DISPLAY INVISIBLE (-4300 7625);
FORCEPROP 0 LAST CDS_SEC 1
J 0
(-4300 7625);
DISPLAY 1.021277 (-4300 7625);
DISPLAY INVISIBLE (-4300 7625);
FORCEADD Q_RES..2
(-4100 7450);
FORCEPROP 1 LAST PART_NUMBER CS21002FB06
J 0
(-4060 7325);
DISPLAY 0.510638 (-4060 7325);
DISPLAY INVISIBLE (-4060 7325);
FORCEPROP 1 LAST MATERIAL CHIP
J 0
(-4060 7375);
DISPLAY 0.638298 (-4060 7375);
FORCEPROP 1 LAST WATTAGE 1/16W
J 0
(-4060 7425);
DISPLAY 0.638298 (-4060 7425);
FORCEPROP 1 LAST VALUE 1K
J 0
(-4055 7525);
DISPLAY 0.638298 (-4055 7525);
FORCEPROP 1 LAST TOLERANCE 1%
J 0
(-4055 7475);
DISPLAY 0.638298 (-4055 7475);
FORCEPROP 1 LAST PACK_TYPE 0402LF
J 0
(-4060 7275);
DISPLAY 0.638298 (-4060 7275);
FORCEPROP 1 LAST $LOCATION R2311
J 0
(-4055 7575);
DISPLAY 0.978723 (-4055 7575);
FORCEPROP 1 LASTPIN (-4100 7550) $PN 1
J 0
(-4095 7512);
DISPLAY 0.787234 (-4095 7512);
PAINT MONO (-4095 7512);
FORCEPROP 1 LASTPIN (-4100 7350) $PN 2
J 0
(-4095 7360);
DISPLAY 0.787234 (-4095 7360);
PAINT MONO (-4095 7360);
FORCEPROP 1 LAST PATH I86
J 0
(-4050 7625);
DISPLAY 0.978723 (-4050 7625);
PAINT WHITE (-4050 7625);
DISPLAY INVISIBLE (-4050 7625);
FORCEPROP 2 LAST CDS_LIB pure_quanta
J 0
(-4100 7450);
DISPLAY INVISIBLE (-4100 7450);
FORCEPROP 0 LAST CDS_LOCATION R2311
J 0
(-4050 7625);
DISPLAY 1.021277 (-4050 7625);
DISPLAY INVISIBLE (-4050 7625);
FORCEPROP 0 LAST $SEC 1
J 0
(-4050 7625);
DISPLAY 0.680851 (-4050 7625);
PAINT MONO (-4050 7625);
DISPLAY INVISIBLE (-4050 7625);
FORCEPROP 0 LAST CDS_SEC 1
J 0
(-4050 7625);
DISPLAY 1.021277 (-4050 7625);
DISPLAY INVISIBLE (-4050 7625);
FORCEADD UNIVERSAL_POWER..1
(-4350 8450);
FORCEPROP 3 LASTPIN (-4350 8400) SIG_NAME P3V3_AUX\g
J 0
(-4340 8410);
DISPLAY 0.659574 (-4340 8410);
PAINT MONO (-4340 8410);
DISPLAY INVISIBLE (-4340 8410);
FORCEPROP 1 LAST HDL_POWER P3V3_AUX
J 1
(-4350 8500);
DISPLAY 0.872340 (-4350 8500);
PAINT GREEN (-4350 8500);
FORCEPROP 1 LAST PATH I87
J 0
(-4300 8475);
DISPLAY 0.872340 (-4300 8475);
PAINT AQUA (-4300 8475);
DISPLAY INVISIBLE (-4300 8475);
FORCEPROP 2 LAST CDS_LIB logical_power
J 0
(-4350 8450);
DISPLAY INVISIBLE (-4350 8450);
FORCEADD UNIVERSAL_GND..1
(-4350 7125);
FORCEPROP 3 LASTPIN (-4350 7175) SIG_NAME GND\g
J 0
(-4340 7185);
DISPLAY 0.659574 (-4340 7185);
PAINT MONO (-4340 7185);
DISPLAY INVISIBLE (-4340 7185);
FORCEPROP 1 LAST HDL_POWER GND
J 1
(-4325 7050);
DISPLAY 0.872340 (-4325 7050);
PAINT GREEN (-4325 7050);
DISPLAY INVISIBLE (-4325 7050);
FORCEPROP 1 LAST PATH I88
J 0
(-4275 7125);
DISPLAY 0.872340 (-4275 7125);
PAINT AQUA (-4275 7125);
DISPLAY INVISIBLE (-4275 7125);
FORCEPROP 2 LAST CDS_LIB logical_power
J 0
(-4350 7125);
DISPLAY INVISIBLE (-4350 7125);
FORCEADD OFFPAGE..2
(2925 8600);
FORCEPROP 2 LAST $XR0 236 
J 0
(3114 8600);
DISPLAY 0.638298 (3114 8600);
PAINT MONO (3114 8600);
FORCEPROP 1 LAST OFFPAGE TRUE
J 0
(3250 8475);
DISPLAY 0.872340 (3250 8475);
PAINT GREEN (3250 8475);
DISPLAY INVISIBLE (3250 8475);
FORCEPROP 1 LAST COMMENT_BODY TRUE
J 0
(2880 8505);
DISPLAY 0.872340 (2880 8505);
PAINT GREEN (2880 8505);
DISPLAY INVISIBLE (2880 8505);
FORCEPROP 2 LAST CDS_LIB standard
J 0
(2925 8600);
PAINT MONO (2925 8600);
DISPLAY INVISIBLE (2925 8600);
FORCEPROP 2 LAST PATH I89
J 0
(3125 8650);
DISPLAY 1.021277 (3125 8650);
DISPLAY INVISIBLE (3125 8650);
FORCEADD OFFPAGE..3
(2925 8850);
FORCEPROP 2 LAST $XR0 236 
J 0
(3139 8850);
DISPLAY 0.638298 (3139 8850);
PAINT MONO (3139 8850);
FORCEPROP 1 LAST COMMENT_BODY TRUE
J 0
(2875 8750);
DISPLAY 0.872340 (2875 8750);
PAINT GREEN (2875 8750);
DISPLAY INVISIBLE (2875 8750);
FORCEPROP 1 LAST OFFPAGE TRUE
J 0
(3250 8725);
DISPLAY 0.872340 (3250 8725);
PAINT GREEN (3250 8725);
DISPLAY INVISIBLE (3250 8725);
FORCEPROP 2 LAST CDS_LIB standard
J 0
(2925 8850);
PAINT MONO (2925 8850);
DISPLAY INVISIBLE (2925 8850);
FORCEPROP 2 LAST PATH I90
J 0
(3150 8900);
DISPLAY 1.021277 (3150 8900);
DISPLAY INVISIBLE (3150 8900);
FORCEADD OFFPAGE..3
(2925 8550);
FORCEPROP 2 LAST $XR0 236 
J 0
(3139 8550);
DISPLAY 0.638298 (3139 8550);
PAINT MONO (3139 8550);
FORCEPROP 2 LAST CDS_LIB standard
J 0
(2925 8550);
PAINT MONO (2925 8550);
DISPLAY INVISIBLE (2925 8550);
FORCEPROP 1 LAST OFFPAGE TRUE
J 0
(3250 8425);
DISPLAY 0.872340 (3250 8425);
PAINT GREEN (3250 8425);
DISPLAY INVISIBLE (3250 8425);
FORCEPROP 1 LAST COMMENT_BODY TRUE
J 0
(2875 8450);
DISPLAY 0.872340 (2875 8450);
PAINT GREEN (2875 8450);
DISPLAY INVISIBLE (2875 8450);
FORCEPROP 2 LAST PATH I91
J 0
(3150 8600);
DISPLAY 1.021277 (3150 8600);
DISPLAY INVISIBLE (3150 8600);
FORCEADD OFFPAGE..2
(2925 8900);
FORCEPROP 2 LAST $XR0 236 
J 0
(3114 8900);
DISPLAY 0.638298 (3114 8900);
PAINT MONO (3114 8900);
FORCEPROP 2 LAST PATH I92
J 0
(3125 8950);
DISPLAY 1.021277 (3125 8950);
DISPLAY INVISIBLE (3125 8950);
FORCEPROP 2 LAST CDS_LIB standard
J 0
(2925 8900);
PAINT MONO (2925 8900);
DISPLAY INVISIBLE (2925 8900);
FORCEPROP 1 LAST COMMENT_BODY TRUE
J 0
(2880 8805);
DISPLAY 0.872340 (2880 8805);
PAINT GREEN (2880 8805);
DISPLAY INVISIBLE (2880 8805);
FORCEPROP 1 LAST OFFPAGE TRUE
J 0
(3250 8775);
DISPLAY 0.872340 (3250 8775);
PAINT GREEN (3250 8775);
DISPLAY INVISIBLE (3250 8775);
FORCEADD OFFPAGE..1
(-2950 8700);
FORCEPROP 2 LAST $XR7 245 
J 0
(-4042 8700);
DISPLAY 0.638298 (-4042 8700);
PAINT MONO (-4042 8700);
FORCEPROP 2 LAST $XR6 233 
J 0
(-3922 8700);
DISPLAY 0.638298 (-3922 8700);
PAINT MONO (-3922 8700);
FORCEPROP 2 LAST $XR5 231 
J 0
(-3802 8700);
DISPLAY 0.638298 (-3802 8700);
PAINT MONO (-3802 8700);
FORCEPROP 2 LAST $XR4 227 
J 0
(-3682 8700);
DISPLAY 0.638298 (-3682 8700);
PAINT MONO (-3682 8700);
FORCEPROP 2 LAST $XR3 191 
J 0
(-3562 8700);
DISPLAY 0.638298 (-3562 8700);
PAINT MONO (-3562 8700);
FORCEPROP 2 LAST $XR2 161 
J 0
(-3442 8700);
DISPLAY 0.638298 (-3442 8700);
PAINT MONO (-3442 8700);
FORCEPROP 2 LAST $XR1 154 
J 0
(-3322 8700);
DISPLAY 0.638298 (-3322 8700);
PAINT MONO (-3322 8700);
FORCEPROP 2 LAST $XR0 215 
J 0
(-3202 8700);
DISPLAY 0.638298 (-3202 8700);
PAINT MONO (-3202 8700);
FORCEPROP 2 LAST CDS_LIB standard
J 0
(-2950 8700);
DISPLAY INVISIBLE (-2950 8700);
FORCEPROP 1 LAST OFFPAGE TRUE
J 0
(-2625 8575);
DISPLAY 0.872340 (-2625 8575);
DISPLAY INVISIBLE (-2625 8575);
FORCEPROP 1 LAST COMMENT_BODY TRUE
J 0
(-2825 8600);
DISPLAY 0.872340 (-2825 8600);
PAINT GREEN (-2825 8600);
DISPLAY INVISIBLE (-2825 8600);
FORCEPROP 2 LAST PATH I93
J 0
(-3225 8750);
DISPLAY 1.021277 (-3225 8750);
DISPLAY INVISIBLE (-3225 8750);
FORCEADD OFFPAGE..2
(-3175 7750);
FORCEPROP 2 LAST $XR0 236 
J 0
(-2986 7750);
DISPLAY 0.638298 (-2986 7750);
PAINT MONO (-2986 7750);
FORCEPROP 1 LAST COMMENT_BODY TRUE
J 0
(-3220 7655);
DISPLAY 0.872340 (-3220 7655);
PAINT GREEN (-3220 7655);
DISPLAY INVISIBLE (-3220 7655);
FORCEPROP 1 LAST OFFPAGE TRUE
J 0
(-2850 7625);
DISPLAY 0.872340 (-2850 7625);
PAINT GREEN (-2850 7625);
DISPLAY INVISIBLE (-2850 7625);
FORCEPROP 2 LAST PATH I95
J 0
(-2975 7800);
DISPLAY 1.021277 (-2975 7800);
DISPLAY INVISIBLE (-2975 7800);
FORCEPROP 2 LAST CDS_LIB standard
J 0
(-3175 7750);
DISPLAY INVISIBLE (-3175 7750);
FORCEADD OFFPAGE..2
(-3175 7700);
FORCEPROP 2 LAST $XR0 236 
J 0
(-2986 7700);
DISPLAY 0.638298 (-2986 7700);
PAINT MONO (-2986 7700);
FORCEPROP 1 LAST OFFPAGE TRUE
J 0
(-2850 7575);
DISPLAY 0.872340 (-2850 7575);
PAINT GREEN (-2850 7575);
DISPLAY INVISIBLE (-2850 7575);
FORCEPROP 1 LAST COMMENT_BODY TRUE
J 0
(-3220 7605);
DISPLAY 0.872340 (-3220 7605);
PAINT GREEN (-3220 7605);
DISPLAY INVISIBLE (-3220 7605);
FORCEPROP 2 LAST PATH I96
J 0
(-2975 7750);
DISPLAY 1.021277 (-2975 7750);
DISPLAY INVISIBLE (-2975 7750);
FORCEPROP 2 LAST CDS_LIB standard
J 0
(-3175 7700);
DISPLAY INVISIBLE (-3175 7700);
FORCEADD Q_RES..1
(-1925 8700);
FORCEPROP 1 LAST PART_NUMBER CS00002JB13
J 0
(-2000 8650);
DISPLAY 0.319149 (-2000 8650);
DISPLAY INVISIBLE (-2000 8650);
FORCEPROP 1 LAST VALUE 0
J 2
(-1725 8700);
DISPLAY 0.510638 (-1725 8700);
FORCEPROP 1 LAST TOLERANCE 5%
J 0
(-1700 8700);
DISPLAY 0.510638 (-1700 8700);
FORCEPROP 1 LAST MATERIAL CHIP
J 0
(-1625 8700);
DISPLAY 0.510638 (-1625 8700);
FORCEPROP 1 LAST $LOCATION R2313
J 0
(-2125 8700);
DISPLAY 0.638298 (-2125 8700);
FORCEPROP 1 LASTPIN (-2025 8700) $PN 1
J 0
(-2013 8712);
DISPLAY 0.787234 (-2013 8712);
PAINT MONO (-2013 8712);
FORCEPROP 1 LASTPIN (-1825 8700) $PN 2
J 0
(-1863 8712);
DISPLAY 0.787234 (-1863 8712);
PAINT MONO (-1863 8712);
FORCEPROP 1 LAST WATTAGE 1/16W
J 2
(-1825 8625);
DISPLAY 0.319149 (-1825 8625);
DISPLAY INVISIBLE (-1825 8625);
FORCEPROP 1 LAST PACK_TYPE 0402LF
J 0
(-1675 8700);
DISPLAY 0.510638 (-1675 8700);
DISPLAY INVISIBLE (-1675 8700);
FORCEPROP 1 LAST PATH I97
J 0
(-1975 8850);
DISPLAY 0.978723 (-1975 8850);
PAINT WHITE (-1975 8850);
DISPLAY INVISIBLE (-1975 8850);
FORCEPROP 2 LAST CDS_LIB pure_quanta
J 0
(-1925 8700);
DISPLAY INVISIBLE (-1925 8700);
FORCEPROP 0 LAST CDS_LOCATION R2313
J 0
(-2125 8750);
DISPLAY 1.021277 (-2125 8750);
DISPLAY INVISIBLE (-2125 8750);
FORCEPROP 0 LAST $SEC 1
J 0
(-2125 8750);
DISPLAY 0.680851 (-2125 8750);
PAINT MONO (-2125 8750);
DISPLAY INVISIBLE (-2125 8750);
FORCEPROP 0 LAST CDS_SEC 1
J 0
(-2125 8750);
DISPLAY 1.021277 (-2125 8750);
DISPLAY INVISIBLE (-2125 8750);
FORCEADD OFFPAGE..1
(-1700 7950);
FORCEPROP 2 LAST $XR0 236 
J 0
(-1982 7950);
DISPLAY 0.638298 (-1982 7950);
PAINT MONO (-1982 7950);
FORCEPROP 2 LAST CDS_LIB standard
J 0
(-1700 7950);
DISPLAY INVISIBLE (-1700 7950);
FORCEPROP 2 LAST PATH I99
J 0
(-1975 8000);
DISPLAY 1.021277 (-1975 8000);
DISPLAY INVISIBLE (-1975 8000);
FORCEPROP 1 LAST COMMENT_BODY TRUE
J 0
(-1575 7850);
DISPLAY 0.872340 (-1575 7850);
PAINT GREEN (-1575 7850);
DISPLAY INVISIBLE (-1575 7850);
FORCEPROP 1 LAST OFFPAGE TRUE
J 0
(-1375 7825);
DISPLAY 0.872340 (-1375 7825);
PAINT GREEN (-1375 7825);
DISPLAY INVISIBLE (-1375 7825);
FORCEADD DNS..2
(1755 4795);
PAINT RED (1755 4795);
FORCEPROP 2 LAST CDS_LIB mstr_misc
J 0
(1755 4795);
PAINT MONO (1755 4795);
DISPLAY INVISIBLE (1755 4795);
FORCEPROP 1 LAST COMMENT_BODY TRUE
J 0
(1755 4795);
DISPLAY INVISIBLE (1755 4795);
FORCEADD DNS..2
(2005 4795);
PAINT RED (2005 4795);
FORCEPROP 2 LAST CDS_LIB mstr_misc
J 0
(2005 4795);
PAINT MONO (2005 4795);
DISPLAY INVISIBLE (2005 4795);
FORCEPROP 1 LAST COMMENT_BODY TRUE
J 0
(2005 4795);
DISPLAY INVISIBLE (2005 4795);
FORCEADD DNS..2
(-4345 8070);
PAINT RED (-4345 8070);
FORCEPROP 1 LAST COMMENT_BODY TRUE
J 0
(-4345 8070);
DISPLAY INVISIBLE (-4345 8070);
FORCEPROP 2 LAST CDS_LIB mstr_misc
J 0
(-4345 8070);
DISPLAY INVISIBLE (-4345 8070);
FORCEADD DNS..2
(-4100 8075);
PAINT RED (-4100 8075);
FORCEPROP 1 LAST COMMENT_BODY TRUE
J 0
(-4100 8075);
DISPLAY INVISIBLE (-4100 8075);
FORCEPROP 2 LAST CDS_LIB mstr_misc
J 0
(-4100 8075);
DISPLAY INVISIBLE (-4100 8075);
FORCEADD QUANTA_TITLE_BLOCK_C..1
(4550 3150);
FORCEPROP 0 LAST CDS_CON_LAST_MODIFIED Fri Aug 25 14:04:00 2023
J 0
(2665 3165);
PAINT MONO (2665 3165);
DISPLAY INVISIBLE (2665 3165);
FORCEPROP 2 LAST CUSTOM_TXT_CDS <XR_PAGE_TITLE>
J 0
(-3340 8400);
DISPLAY 0.638298 (-3340 8400);
PAINT PINK (-3340 8400);
DISPLAY INVISIBLE (-3340 8400);
FORCEPROP 2 LAST CUSTOM_TXT_CDS <CON_LAST_MODIFIED>
J 0
(2665 3165);
DISPLAY 0.978723 (2665 3165);
FORCEPROP 2 LAST CUSTOM_TXT_CDS <NAME_2>
J 0
(1375 3200);
FORCEPROP 2 LAST CUSTOM_TXT_CDS <NAME_1>
J 0
(1375 3325);
FORCEPROP 2 LAST CUSTOM_TXT_CDS <Q_NUMBER>
J 0
(3147 3253);
DISPLAY 1.212766 (3147 3253);
FORCEPROP 2 LAST CUSTOM_TXT_CDS <Q_PROJ>
J 0
(2168 3252);
DISPLAY 1.212766 (2168 3252);
FORCEPROP 2 LAST CUSTOM_TXT_CDS <Q_REV>
J 0
(4366 3253);
DISPLAY 1.212766 (4366 3253);
FORCEPROP 2 LAST CUSTOM_TXT_CDS <CON_PAGE_NUM> OF <CON_TOTAL_PAGES>
J 0
(4104 3168);
DISPLAY 0.978723 (4104 3168);
FORCEPROP 1 LAST Q_TITLE SMBUS - CPU0 &1 S3M SMBUS
J 0
(-4716 3176);
DISPLAY 2.446809 (-4716 3176);
PAINT GREEN (-4716 3176);
FORCEPROP 1 LAST Q_DEPT 
J 1
(787 3199);
DISPLAY 1.957447 (787 3199);
PAINT GREEN (787 3199);
FORCEPROP 2 LAST CDS_XR_PAGE_TITLE CR-236 : @S9S_MB_2U_LIB.S9S_MB_2U(SCH_1):PAGE236
J 0
(-3340 8400);
DISPLAY 0.638298 (-3340 8400);
PAINT PINK (-3340 8400);
DISPLAY INVISIBLE (-3340 8400);
FORCEPROP 2 LAST CDS_LIB pure_quanta
J 0
(4550 3150);
PAINT MONO (4550 3150);
DISPLAY INVISIBLE (4550 3150);
FORCEPROP 1 LAST CDS_LMAN_SYM_OUTLINE -9475,6775,100,-125
J 0
(4550 3150);
DISPLAY 0.468085 (4550 3150);
PAINT GREEN (4550 3150);
DISPLAY INVISIBLE (4550 3150);
FORCEPROP 1 LAST COMMENT_BODY TRUE
J 0
(4562 3137);
DISPLAY 0.978723 (4562 3137);
PAINT GREEN (4562 3137);
DISPLAY INVISIBLE (4562 3137);
FORCEPROP 2 LAST PAGE_BORDER TRUE
J 0
(-3340 8400);
DISPLAY 0.638298 (-3340 8400);
PAINT PINK (-3340 8400);
DISPLAY INVISIBLE (-3340 8400);
WIRE 16 -1 (1150 4700)(1150 4625);
WIRE 16 -1 (-2725 6500)(-2725 6425);
WIRE 16 -1 (-1825 4700)(-1825 4625);
WIRE 16 -1 (-475 4700)(-475 4625);
WIRE 16 -1 (-4350 8400)(-4350 8325);
WIRE 16 -1 (-2800 9250)(-2800 9450);
WIRE 16 -1 (-975 9550)(-975 9475);
WIRE 16 -1 (4200 9500)(4200 9425);
WIRE 16 -1 (4200 7025)(4200 6800);
WIRE 16 -1 (-1825 6500)(-1825 6425);
WIRE 16 -1 (-2725 4700)(-2725 4625);
WIRE 16 -1 (1150 6500)(1150 6425);
WIRE 16 -1 (-475 6500)(-475 6425);
WIRE 16 -1 (-1675 3600)(-1675 3700);
WIRE 16 -1 (-1825 4325)(-1825 4250);
WIRE 16 -1 (-1675 5400)(-1675 5500);
WIRE 16 -1 (-1825 6125)(-1825 6050);
WIRE 16 -1 (-475 4325)(-475 4250);
WIRE 16 -1 (-475 6125)(-475 6050);
WIRE 16 -1 (-4350 7250)(-4350 7175);
WIRE 16 -1 (-4100 7250)(-4350 7250);
WIRE 16 -1 (-4350 7350)(-4350 7250);
WIRE 16 -1 (-975 9175)(-975 9100);
WIRE 16 -1 (-825 7725)(-825 7900);
WIRE 16 -1 (-625 4100)(-700 4100);
WIRE 16 -1 (-625 4100)(-625 4625);
WIRE 16 -1 (-475 4625)(-625 4625);
WIRE 16 -1 (-475 4625)(-475 4525);
WIRE 16 -1 (1750 3950)(2125 3950);
WIRE 16 -1 (1750 4700)(1750 3950);
WIRE 16 -1 (1150 3950)(-700 3950);
FORCEPROP 0 LAST CDS_PHYS_NET_NAME SMB_S3M_CPU1_3V3AUX_SCL
J 0
(-660 3998);
PAINT MONO (-660 3998);
DISPLAY INVISIBLE (-660 3998);
FORCEPROP 2 LAST SIG_NAME SMB_S3M_CPU1_3V3AUX_SCL
J 0
(-335 3960);
DISPLAY 0.510638 (-335 3960);
PAINT WHITE (-335 3960);
WIRE 16 -1 (1150 3950)(1750 3950);
WIRE 16 -1 (1150 4300)(1150 3950);
WIRE 16 -1 (4200 6450)(3750 6450);
WIRE 16 -1 (3750 6500)(4200 6500);
WIRE 16 -1 (4200 6500)(4200 6450);
WIRE 16 -1 (4200 6750)(3750 6750);
WIRE 16 -1 (4200 6750)(4200 6500);
WIRE 16 -1 (4200 6800)(3750 6800);
WIRE 16 -1 (4200 6800)(4200 6750);
WIRE 16 -1 (-2800 9050)(-2800 8800);
WIRE 16 -1 (-700 8800)(-2800 8800);
FORCEPROP 2 LAST SIG_NAME PCA9545_S3M_INT_N
J 0
(-1610 8810);
DISPLAY 0.638298 (-1610 8810);
PAINT WHITE (-1610 8810);
WIRE 16 -1 (-2900 8700)(-2025 8700);
FORCEPROP 0 LAST CDS_PHYS_NET_NAME RST_SMB_SWITCH_N
J 0
(-2860 8748);
PAINT MONO (-2860 8748);
DISPLAY INVISIBLE (-2860 8748);
FORCEPROP 2 LAST SIG_NAME RST_SMB_SWITCH_N
J 0
(-2785 8710);
DISPLAY 0.638298 (-2785 8710);
PAINT WHITE (-2785 8710);
WIRE 16 -1 (3275 9425)(3275 9300);
WIRE 16 -1 (3600 9425)(3275 9425);
WIRE 16 -1 (3600 9300)(3600 9425);
WIRE 16 -1 (3900 9425)(3600 9425);
WIRE 16 -1 (3900 9300)(3900 9425);
WIRE 16 -1 (4200 9425)(4200 9300);
WIRE 16 -1 (4200 9425)(3900 9425);
WIRE 16 -1 (1150 4625)(1150 4500);
WIRE 16 -1 (1350 4500)(1350 4625);
WIRE 16 -1 (1350 4625)(1150 4625);
WIRE 16 -1 (-625 5900)(-700 5900);
WIRE 16 -1 (-625 5900)(-625 6425);
WIRE 16 -1 (-475 6425)(-625 6425);
WIRE 16 -1 (-475 6425)(-475 6325);
WIRE 16 -1 (-1550 5900)(-1675 5900);
WIRE 16 -1 (-1825 6425)(-1825 6325);
WIRE 16 -1 (-1675 5900)(-1675 6425);
WIRE 16 -1 (-1675 6425)(-1825 6425);
WIRE 16 -1 (-1675 5500)(-1550 5500);
WIRE 16 -1 (-1550 4100)(-1675 4100);
WIRE 16 -1 (-1825 4625)(-1825 4525);
WIRE 16 -1 (-1675 4100)(-1675 4625);
WIRE 16 -1 (-1675 4625)(-1825 4625);
WIRE 16 -1 (-1675 3700)(-1550 3700);
WIRE 16 -1 (-2725 6425)(-2725 6300);
WIRE 16 -1 (-2500 6425)(-2725 6425);
WIRE 16 -1 (-2500 6300)(-2500 6425);
WIRE 16 -1 (-2725 4625)(-2725 4500);
WIRE 16 -1 (-2500 4625)(-2725 4625);
WIRE 16 -1 (-2500 4500)(-2500 4625);
WIRE 16 -1 (1150 6425)(1150 6300);
WIRE 16 -1 (1350 6425)(1150 6425);
WIRE 16 -1 (1350 6300)(1350 6425);
WIRE 16 -1 (-700 8950)(-825 8950);
WIRE 16 -1 (-975 9475)(-975 9375);
WIRE 16 -1 (-825 8950)(-825 9475);
WIRE 16 -1 (-825 9475)(-975 9475);
WIRE 16 -1 (-4350 8325)(-4350 8200);
WIRE 16 -1 (-4100 8325)(-4350 8325);
WIRE 16 -1 (-4100 8200)(-4100 8325);
WIRE 16 -1 (-4100 7350)(-4100 7250);
WIRE 16 -1 (-700 7900)(-825 7900);
WIRE 16 -1 (4200 7900)(4200 9100);
WIRE 16 -1 (200 7900)(4200 7900);
FORCEPROP 2 LAST SIG_NAME PCA9543_S3M_INT3_N
J 0
(265 7910);
DISPLAY 0.808511 (265 7910);
PAINT WHITE (265 7910);
WIRE 16 -1 (-700 8000)(-1650 8000);
FORCEPROP 2 LAST SIG_NAME PCA9543_S3M_ADDR1
J 0
(-1385 8010);
DISPLAY 0.638298 (-1385 8010);
PAINT WHITE (-1385 8010);
WIRE 16 -1 (-700 7950)(-1650 7950);
FORCEPROP 2 LAST SIG_NAME PCA9543_S3M_ADDR0
J 0
(-1385 7960);
DISPLAY 0.638298 (-1385 7960);
PAINT WHITE (-1385 7960);
WIRE 16 -1 (200 8000)(1375 8000);
FORCEPROP 2 LAST SIG_NAME SMB_S3M_CPU1_PIROM_3V3AUX_SCL_R
J 0
(265 8010);
DISPLAY 0.702128 (265 8010);
PAINT WHITE (265 8010);
WIRE 16 -1 (3900 8200)(3900 9100);
WIRE 16 -1 (200 8200)(3900 8200);
FORCEPROP 2 LAST SIG_NAME PCA9543_S3M_INT2_N
J 0
(265 8210);
DISPLAY 0.808511 (265 8210);
PAINT WHITE (265 8210);
WIRE 16 -1 (-1825 8700)(-700 8700);
FORCEPROP 0 LAST CDS_PHYS_NET_NAME RST_SMB_PCIE1_N
J 0
(-1785 8748);
PAINT MONO (-1785 8748);
DISPLAY INVISIBLE (-1785 8748);
FORCEPROP 2 LAST SIG_NAME RST_SMB_S3M_N
J 0
(-1385 8710);
DISPLAY 0.638298 (-1385 8710);
PAINT WHITE (-1385 8710);
WIRE 16 -1 (-4100 7700)(-4100 7550);
WIRE 16 -1 (-4100 8000)(-4100 7700);
WIRE 16 -1 (-3225 7700)(-4100 7700);
FORCEPROP 2 LAST SIG_NAME PCA9543_S3M_ADDR0
J 0
(-3990 7710);
DISPLAY 0.638298 (-3990 7710);
PAINT WHITE (-3990 7710);
WIRE 16 -1 (-4350 7750)(-4350 7550);
WIRE 16 -1 (-4350 8000)(-4350 7750);
WIRE 16 -1 (-4350 7750)(-3225 7750);
FORCEPROP 2 LAST SIG_NAME PCA9543_S3M_ADDR1
J 0
(-3985 7760);
DISPLAY 0.638298 (-3985 7760);
PAINT WHITE (-3985 7760);
WIRE 16 -1 (-1750 8850)(-700 8850);
FORCEPROP 2 LAST SIG_NAME SMB_S3M_CPU_3V3AUX_SDA
J 0
(-1610 8860);
DISPLAY 0.680851 (-1610 8860);
PAINT WHITE (-1610 8860);
WIRE 16 -1 (3275 8800)(200 8800);
FORCEPROP 2 LAST SIG_NAME PCA9543_S3M_INT0_N
J 0
(265 8810);
DISPLAY 0.808511 (265 8810);
PAINT WHITE (265 8810);
WIRE 16 -1 (3275 9100)(3275 8800);
WIRE 16 -1 (200 8850)(1375 8850);
FORCEPROP 2 LAST SIG_NAME SMB_S3M_CPU0_3V3AUX_SDA_R
J 0
(265 8860);
DISPLAY 0.702128 (265 8860);
PAINT WHITE (265 8860);
WIRE 16 2175 (-3425 3925)(-2750 3925);
WIRE 16 2175 (-2750 3925)(-2750 3800);
WIRE 16 2175 (-3425 3925)(-3425 3800);
WIRE 16 2175 (-3425 3800)(-2750 3800);
WIRE 16 -1 (-1550 3950)(-2725 3950);
FORCEPROP 2 LAST SIG_NAME SMB_S3M_CPU1_R_SCL
J 0
(-2385 3960);
DISPLAY 0.510638 (-2385 3960);
PAINT WHITE (-2385 3960);
WIRE 16 -1 (-2725 4300)(-2725 3950);
WIRE 16 -1 (-3075 3950)(-2725 3950);
FORCEPROP 0 LAST CDS_PHYS_NET_NAME SMB_S3M_CPU1_R_SCL
J 0
(-3035 3998);
PAINT MONO (-3035 3998);
DISPLAY INVISIBLE (-3035 3998);
WIRE 16 -1 (-4025 3850)(-3275 3850);
FORCEPROP 0 LAST CDS_PHYS_NET_NAME SMB_S3M_CPU1_SDA
J 0
(-3985 3898);
PAINT MONO (-3985 3898);
DISPLAY INVISIBLE (-3985 3898);
FORCEPROP 2 LAST SIG_NAME SMB_S3M_CPU1_SDA
J 0
(-3910 3860);
DISPLAY 0.510638 (-3910 3860);
PAINT WHITE (-3910 3860);
WIRE 16 -1 (-1550 3850)(-2500 3850);
FORCEPROP 2 LAST SIG_NAME SMB_S3M_CPU1_R_SDA
J 0
(-2385 3860);
DISPLAY 0.510638 (-2385 3860);
PAINT WHITE (-2385 3860);
WIRE 16 -1 (-2500 4300)(-2500 3850);
WIRE 16 -1 (-3075 3850)(-2500 3850);
FORCEPROP 0 LAST CDS_PHYS_NET_NAME SMB_S3M_CPU1_R_SDA
J 0
(-3035 3898);
PAINT MONO (-3035 3898);
DISPLAY INVISIBLE (-3035 3898);
WIRE 16 2175 (-3425 5575)(-2750 5575);
WIRE 16 2175 (-2750 5725)(-2750 5575);
WIRE 16 2175 (-3425 5725)(-3425 5575);
WIRE 16 2175 (-3425 5725)(-2750 5725);
WIRE 16 -1 (-4025 5650)(-3275 5650);
FORCEPROP 0 LAST CDS_PHYS_NET_NAME SMB_S3M_CPU0_SDA
J 0
(-3985 5698);
PAINT MONO (-3985 5698);
DISPLAY INVISIBLE (-3985 5698);
FORCEPROP 2 LAST SIG_NAME SMB_S3M_CPU0_SDA
J 0
(-3910 5660);
DISPLAY 0.510638 (-3910 5660);
PAINT WHITE (-3910 5660);
WIRE 16 -1 (-2500 6100)(-2500 5650);
WIRE 16 -1 (-2500 5650)(-1550 5650);
FORCEPROP 2 LAST SIG_NAME SMB_S3M_CPU0_R_SDA
J 0
(-2385 5660);
DISPLAY 0.510638 (-2385 5660);
PAINT WHITE (-2385 5660);
WIRE 16 -1 (-3075 5650)(-2500 5650);
FORCEPROP 0 LAST CDS_PHYS_NET_NAME SMB_S3M_CPU0_R_SDA
J 0
(-3035 5698);
PAINT MONO (-3035 5698);
DISPLAY INVISIBLE (-3035 5698);
WIRE 16 -1 (-3075 5750)(-2725 5750);
FORCEPROP 0 LAST CDS_PHYS_NET_NAME SMB_S3M_CPU0_R_SCL
J 0
(-3035 5798);
PAINT MONO (-3035 5798);
DISPLAY INVISIBLE (-3035 5798);
WIRE 16 -1 (-2725 5750)(-1550 5750);
FORCEPROP 2 LAST SIG_NAME SMB_S3M_CPU0_R_SCL
J 0
(-2385 5760);
DISPLAY 0.510638 (-2385 5760);
PAINT WHITE (-2385 5760);
WIRE 16 -1 (-2725 6100)(-2725 5750);
WIRE 16 -1 (-1750 8900)(-700 8900);
FORCEPROP 2 LAST SIG_NAME SMB_S3M_CPU_3V3AUX_SCL
J 0
(-1610 8910);
DISPLAY 0.680851 (-1610 8910);
PAINT WHITE (-1610 8910);
WIRE 16 -1 (-700 5500)(225 5500);
FORCEPROP 0 LAST CDS_PHYS_NET_NAME TP_SMB_S3M_CPU0_EN
J 0
(-660 5548);
PAINT MONO (-660 5548);
DISPLAY INVISIBLE (-660 5548);
FORCEPROP 2 LAST SIG_NAME TP_SMB_S3M_CPU0_EN
J 0
(-335 5510);
DISPLAY 0.510638 (-335 5510);
PAINT WHITE (-335 5510);
WIRE 16 -1 (-700 3700)(225 3700);
FORCEPROP 0 LAST CDS_PHYS_NET_NAME TP_SMB_S3M_CPU1_EN
J 0
(-660 3748);
PAINT MONO (-660 3748);
DISPLAY INVISIBLE (-660 3748);
FORCEPROP 2 LAST SIG_NAME TP_SMB_S3M_CPU1_EN
J 0
(-335 3710);
DISPLAY 0.510638 (-335 3710);
PAINT WHITE (-335 3710);
WIRE 16 -1 (1575 8600)(2875 8600);
FORCEPROP 2 LAST SIG_NAME SMB_S3M_CPU1_3V3AUX_SCL
J 0
(1915 8610);
DISPLAY 0.702128 (1915 8610);
PAINT WHITE (1915 8610);
WIRE 16 -1 (1575 8850)(2875 8850);
FORCEPROP 2 LAST SIG_NAME SMB_S3M_CPU0_3V3AUX_SDA
J 0
(1965 8860);
DISPLAY 0.702128 (1965 8860);
PAINT WHITE (1965 8860);
WIRE 16 -1 (200 7950)(1375 7950);
FORCEPROP 2 LAST SIG_NAME SMB_S3M_CPU1_PIROM_3V3AUX_SDA_R
J 0
(265 7960);
DISPLAY 0.702128 (265 7960);
PAINT WHITE (265 7960);
WIRE 16 -1 (200 8300)(1375 8300);
FORCEPROP 2 LAST SIG_NAME SMB_S3M_CPU0_PIROM_3V3AUX_SCL_R
J 0
(265 8310);
DISPLAY 0.702128 (265 8310);
PAINT WHITE (265 8310);
WIRE 16 -1 (1575 8900)(2875 8900);
FORCEPROP 2 LAST SIG_NAME SMB_S3M_CPU0_3V3AUX_SCL
J 0
(1965 8910);
DISPLAY 0.702128 (1965 8910);
PAINT WHITE (1965 8910);
WIRE 16 -1 (1575 8550)(2875 8550);
FORCEPROP 2 LAST SIG_NAME SMB_S3M_CPU1_3V3AUX_SDA
J 0
(1915 8560);
DISPLAY 0.702128 (1915 8560);
PAINT WHITE (1915 8560);
WIRE 16 -1 (2000 4900)(2000 5650);
WIRE 16 -1 (2125 5650)(2000 5650);
WIRE 16 -1 (1350 6100)(1350 5650);
WIRE 16 -1 (2000 5650)(1350 5650);
WIRE 16 -1 (-700 5650)(1350 5650);
FORCEPROP 0 LAST CDS_PHYS_NET_NAME SMB_S3M_CPU0_3V3AUX_SDA
J 0
(-660 5698);
PAINT MONO (-660 5698);
DISPLAY INVISIBLE (-660 5698);
FORCEPROP 2 LAST SIG_NAME SMB_S3M_CPU0_3V3AUX_SDA
J 0
(-335 5660);
DISPLAY 0.510638 (-335 5660);
PAINT WHITE (-335 5660);
WIRE 16 -1 (1750 4900)(1750 5750);
WIRE 16 -1 (1750 5750)(2125 5750);
WIRE 16 -1 (1150 6100)(1150 5750);
WIRE 16 -1 (1750 5750)(1150 5750);
WIRE 16 -1 (-700 5750)(1150 5750);
FORCEPROP 0 LAST CDS_PHYS_NET_NAME SMB_S3M_CPU0_3V3AUX_SCL
J 0
(-660 5798);
PAINT MONO (-660 5798);
DISPLAY INVISIBLE (-660 5798);
FORCEPROP 2 LAST SIG_NAME SMB_S3M_CPU0_3V3AUX_SCL
J 0
(-335 5760);
DISPLAY 0.510638 (-335 5760);
PAINT WHITE (-335 5760);
WIRE 16 -1 (2125 3850)(2000 3850);
WIRE 16 -1 (2000 4700)(2000 3850);
WIRE 16 -1 (1350 3850)(-700 3850);
FORCEPROP 0 LAST CDS_PHYS_NET_NAME SMB_S3M_CPU1_3V3AUX_SDA
J 0
(-660 3898);
PAINT MONO (-660 3898);
DISPLAY INVISIBLE (-660 3898);
FORCEPROP 2 LAST SIG_NAME SMB_S3M_CPU1_3V3AUX_SDA
J 0
(-335 3860);
DISPLAY 0.510638 (-335 3860);
PAINT WHITE (-335 3860);
WIRE 16 -1 (1350 3850)(2000 3850);
WIRE 16 -1 (1350 4300)(1350 3850);
WIRE 16 -1 (200 8900)(1375 8900);
FORCEPROP 2 LAST SIG_NAME SMB_S3M_CPU0_3V3AUX_SCL_R
J 0
(265 8910);
DISPLAY 0.702128 (265 8910);
PAINT WHITE (265 8910);
WIRE 16 -1 (1575 8300)(2875 8300);
FORCEPROP 2 LAST SIG_NAME SMB_S3M_CPU0_PIROM_3V3AUX_SCL
J 0
(1915 8310);
DISPLAY 0.702128 (1915 8310);
PAINT WHITE (1915 8310);
WIRE 16 -1 (1575 8250)(2875 8250);
FORCEPROP 2 LAST SIG_NAME SMB_S3M_CPU0_PIROM_3V3AUX_SDA
J 0
(1915 8260);
DISPLAY 0.702128 (1915 8260);
PAINT WHITE (1915 8260);
WIRE 16 -1 (3550 6500)(2200 6500);
FORCEPROP 2 LAST SIG_NAME SMB_S3M_CPU1_PIROM_3V3AUX_SCL
J 0
(2315 6510);
DISPLAY 0.680851 (2315 6510);
PAINT WHITE (2315 6510);
WIRE 16 -1 (3550 6450)(2200 6450);
FORCEPROP 2 LAST SIG_NAME SMB_S3M_CPU1_PIROM_3V3AUX_SDA
J 0
(2315 6460);
DISPLAY 0.680851 (2315 6460);
PAINT WHITE (2315 6460);
WIRE 16 -1 (1575 7950)(2875 7950);
FORCEPROP 2 LAST SIG_NAME SMB_S3M_CPU1_PIROM_3V3AUX_SDA
J 0
(1915 7960);
DISPLAY 0.702128 (1915 7960);
PAINT WHITE (1915 7960);
WIRE 16 -1 (1575 8000)(2875 8000);
FORCEPROP 2 LAST SIG_NAME SMB_S3M_CPU1_PIROM_3V3AUX_SCL
J 0
(1915 8010);
DISPLAY 0.702128 (1915 8010);
PAINT WHITE (1915 8010);
WIRE 16 -1 (200 8250)(1375 8250);
FORCEPROP 2 LAST SIG_NAME SMB_S3M_CPU0_PIROM_3V3AUX_SDA_R
J 0
(265 8260);
DISPLAY 0.702128 (265 8260);
PAINT WHITE (265 8260);
WIRE 16 -1 (200 8600)(1375 8600);
FORCEPROP 2 LAST SIG_NAME SMB_S3M_CPU1_3V3AUX_SCL_R
J 0
(265 8610);
DISPLAY 0.702128 (265 8610);
PAINT WHITE (265 8610);
WIRE 16 -1 (200 8550)(1375 8550);
FORCEPROP 2 LAST SIG_NAME SMB_S3M_CPU1_3V3AUX_SDA_R
J 0
(265 8560);
DISPLAY 0.702128 (265 8560);
PAINT WHITE (265 8560);
WIRE 16 -1 (3600 8500)(3600 9100);
WIRE 16 -1 (200 8500)(3600 8500);
FORCEPROP 2 LAST SIG_NAME PCA9543_S3M_INT1_N
J 0
(265 8510);
DISPLAY 0.808511 (265 8510);
PAINT WHITE (265 8510);
WIRE 16 -1 (3550 6750)(2200 6750);
FORCEPROP 2 LAST SIG_NAME SMB_S3M_CPU0_PIROM_3V3AUX_SDA
J 0
(2315 6760);
DISPLAY 0.680851 (2315 6760);
PAINT WHITE (2315 6760);
WIRE 16 -1 (3550 6800)(2200 6800);
FORCEPROP 2 LAST SIG_NAME SMB_S3M_CPU0_PIROM_3V3AUX_SCL
J 0
(2315 6810);
DISPLAY 0.680851 (2315 6810);
PAINT WHITE (2315 6810);
WIRE 16 -1 (-4025 5750)(-3275 5750);
FORCEPROP 0 LAST CDS_PHYS_NET_NAME SMB_S3M_CPU0_SCL
J 0
(-3985 5798);
PAINT MONO (-3985 5798);
DISPLAY INVISIBLE (-3985 5798);
FORCEPROP 2 LAST SIG_NAME SMB_S3M_CPU0_SCL
J 0
(-3910 5760);
DISPLAY 0.510638 (-3910 5760);
PAINT WHITE (-3910 5760);
WIRE 16 -1 (-4025 3950)(-3275 3950);
FORCEPROP 0 LAST CDS_PHYS_NET_NAME SMB_S3M_CPU1_SCL
J 0
(-3985 3998);
PAINT MONO (-3985 3998);
DISPLAY INVISIBLE (-3985 3998);
FORCEPROP 2 LAST SIG_NAME SMB_S3M_CPU1_SCL
J 0
(-3910 3960);
DISPLAY 0.510638 (-3910 3960);
PAINT WHITE (-3910 3960);
DOT 1 (-2500 5650);
DOT 1 (4200 9425);
DOT 1 (3600 9425);
DOT 1 (3900 9425);
DOT 1 (-975 9475);
DOT 1 (-4350 7250);
DOT 1 (-4350 7750);
DOT 1 (-4350 8325);
DOT 1 (-4100 7700);
DOT 1 (4200 6500);
DOT 1 (4200 6750);
DOT 1 (4200 6800);
DOT 1 (1750 5750);
DOT 1 (2000 5650);
DOT 1 (1350 5650);
DOT 1 (2000 3850);
DOT 1 (1750 3950);
DOT 1 (1350 3850);
DOT 1 (1150 6425);
DOT 1 (1150 5750);
DOT 1 (-475 6425);
DOT 1 (1150 4625);
DOT 1 (1150 3950);
DOT 1 (-475 4625);
DOT 1 (-1825 6425);
DOT 1 (-2725 6425);
DOT 1 (-2725 5750);
DOT 1 (-1825 4625);
DOT 1 (-2725 4625);
DOT 1 (-2725 3950);
DOT 1 (-2500 3850);
FORCENOTE
PCA9545 ADDR: 0X70
(-1050 7425) 0;
DISPLAY LEFT (-1050 7425);
DISPLAY 1.595745 (-1050 7425);
PAINT SKYBLUE (-1050 7425);
FORCENOTE
20211129 R996 CHANGE TO 33 OHM
(-3900 3625) 0;
DISPLAY LEFT (-3900 3625);
DISPLAY 1.063830 (-3900 3625);
PAINT WHITE (-3900 3625);
FORCENOTE
20211129 R996 CHANGE TO 10 OHM
(-3900 3700) 0;
DISPLAY LEFT (-3900 3700);
DISPLAY 1.063830 (-3900 3700);
PAINT WHITE (-3900 3700);
FORCENOTE
20211215 R994 CHANGE TO 33 OHM
(-3800 5375) 0;
DISPLAY LEFT (-3800 5375);
DISPLAY 1.063830 (-3800 5375);
PAINT WHITE (-3800 5375);
FORCENOTE
20211129 R994 CHANGE TO 10 OHM
(-3800 5450) 0;
DISPLAY LEFT (-3800 5450);
DISPLAY 1.063830 (-3800 5450);
PAINT WHITE (-3800 5450);
FORCENOTE
20210818 MODIFY FOR GT
(-4475 9650) 0;
DISPLAY LEFT (-4475 9650);
DISPLAY 2.510638 (-4475 9650);
PAINT PINK (-4475 9650);
QUIT
